G04 ================== begin FILE IDENTIFICATION RECORD ==================*
G04 Layout Name:  x887571-005_osp.brd*
G04 Film Name:    top*
G04 File Format:  Gerber RS274X*
G04 File Origin:  Cadence Allegro 16.3-S036*
G04 Origin Date:  Thu Jul 03 00:06:57 2014*
G04 *
G04 Layer:  VIA CLASS/TOP*
G04 Layer:  PIN/TOP*
G04 Layer:  ETCH/TOP*
G04 Layer:  DRAWING FORMAT/COMMON TEXT*
G04 Layer:  BOARD GEOMETRY/TOP LAYER TEXT*
G04 *
G04 Offset:    (0.0000 0.0000)*
G04 Mirror:    No*
G04 Mode:      Positive*
G04 Rotation:  0*
G04 FullContactRelief:  No*
G04 UndefLineWidth:     4.0000*
G04 ================== end FILE IDENTIFICATION RECORD ====================*
%FSLAX25Y25*MOIN*%
%IR0*IPPOS*OFA0.00000B0.00000*MIA0B0*SFA1.00000B1.00000*%
%ADD25R,.135X.05*%
%ADD20C,.02*%
%ADD15R,.032X.197*%
%ADD13C,.04*%
%ADD12C,.022*%
%ADD22C,.05*%
%ADD16C,.032*%
%ADD28C,.061*%
%ADD21C,.025*%
%ADD34C,.044*%
%ADD11C,.026*%
%ADD35C,.027*%
%ADD14C,.054*%
%ADD18R,.032X.032*%
%ADD30C,.058*%
%ADD37C,.079*%
%ADD26R,.054X.054*%
%ADD31R,.079X.079*%
%ADD32R,.023X.02*%
%ADD23R,.02X.023*%
%ADD29O,.014X.071*%
%ADD19R,.032X.028*%
%ADD33O,.02X.079*%
%ADD27R,.028X.032*%
%ADD24C,.22*%
%ADD36C,.15*%
%ADD17R,.372X.248*%
%ADD10C,.276*%
%ADD38C,.01*%
%ADD39C,.012*%
%ADD40C,.013*%
%ADD41C,.015*%
%ADD42C,.004*%
%ADD43C,.005*%
%ADD44C,.006*%
%ADD45C,.0042*%
%ADD46C,.007*%
%ADD47C,.008*%
%ADD49C,.032*%
%ADD55C,.073*%
%ADD52C,.046*%
%ADD54C,.098*%
%ADD53C,.099*%
%ADD51C,.130001*%
%ADD48C,.154001*%
%ADD50C,.186001*%
%ADD56R,.098X.098*%
G75*
%LPD*%
G75*
G36*
G01X-1629300Y-168025D02*
G03X-1661215Y-161142I-16700J0D01*
G01Y-174908D01*
G03X-1629300Y-168025I15215J6883D01*
G37*
G36*
G01X-1453650Y-183850D02*
X-1455500Y-182000D01*
Y-67600D01*
X-1464000Y-59100D01*
X-1616700D01*
X-1618900Y-56900D01*
Y-21800D01*
G03X-1617331Y-18937I-1827J2863D01*
G01Y16258D01*
X-1616509Y17080D01*
X-1542110D01*
Y-17590D01*
X-1542105Y-17595D01*
Y-20985D01*
X-1537300Y-25790D01*
X-1462790D01*
X-1460500Y-23500D01*
X-1444500D01*
X-1439241Y-18241D01*
Y9213D01*
G02X-1432598Y15855I6643J0D01*
G01X-1421918D01*
G02X-1421461Y15152I0J-500D01*
G03X-1418539I1461J-652D01*
G02X-1418082Y15855I457J204D01*
G01X-1397166D01*
G02X-1396773Y15045I0J-500D01*
G03X-1394263I1255J-992D01*
G02X-1393871Y15855I392J310D01*
G01X-1371918D01*
G02X-1371461Y15152I0J-500D01*
G03X-1368539I1461J-652D01*
G02X-1368082Y15855I457J204D01*
G01X-1346918D01*
G02X-1346461Y15152I0J-500D01*
G03X-1343539I1461J-652D01*
G02X-1343082Y15855I457J204D01*
G01X-1325500D01*
Y-2900D01*
X-1337700D01*
Y-9100D01*
X-1325500D01*
Y-14841D01*
X-1326700D01*
Y-18841D01*
X-1325500D01*
Y-19959D01*
X-1326700D01*
Y-23959D01*
X-1326100D01*
Y-26959D01*
G03X-1325500Y-28208I1600J0D01*
G01Y-80517D01*
X-1325971Y-80989D01*
G03X-1324405Y-83660I1131J-1131D01*
G01X-1324372Y-83650D01*
X-1323828D01*
Y-83800D01*
X-1323200D01*
X-1322500Y-84500D01*
X-1307500D01*
X-1303849Y-88151D01*
X-1308050Y-92353D01*
Y-93942D01*
G03X-1305596Y-94006I1200J-1058D01*
G01X-1305650Y-93938D01*
Y-93347D01*
X-1302151Y-89849D01*
X-1287700Y-104300D01*
Y-181550D01*
X-1290000Y-183850D01*
X-1453650D01*
G37*
G36*
G01X-1506669Y-150370D02*
G03Y-159531I-16060J-4581D01*
G01Y-150370D01*
G37*
G36*
G01X-1462240Y-22240D02*
X-1463880Y-23880D01*
X-1535280D01*
X-1539300Y-19860D01*
Y17080D01*
X-1462240D01*
Y-22240D01*
G37*
G36*
G01X-977368Y-181600D02*
X-989144D01*
G02X-989426Y-180687I0J500D01*
G03X-989774Y-176279I-1440J2105D01*
G02Y-175375I214J452D01*
G03X-991609Y-170631I-1093J2304D01*
G01X-993008Y-169232D01*
Y-165291D01*
X-988616D01*
Y-163247D01*
G03Y-160847I-2250J1200D01*
G01Y-157735D01*
G03Y-155335I-2250J1200D01*
G01Y-153291D01*
X-993008D01*
Y-148756D01*
X-988616D01*
Y-146712D01*
G03Y-144312I-2250J1200D01*
G01Y-141200D01*
G03Y-138800I-2250J1200D01*
G01Y-136756D01*
X-993008D01*
Y-127012D01*
X-998620Y-121400D01*
X-1017517D01*
X-1017768Y-121651D01*
X-1017854Y-121661D01*
G03X-1019253Y-123020I184J-1589D01*
G02X-1020102Y-123301I-495J72D01*
G01X-1020541Y-122862D01*
X-1020551Y-122776D01*
G03X-1022324Y-124549I-1589J-184D01*
G01X-1022238Y-124559D01*
X-1022024Y-124773D01*
G02X-1022201Y-125200I-177J-177D01*
G01X-1032164D01*
X-1033941Y-126977D01*
X-1034027Y-126987D01*
G03X-1032254Y-128760I184J-1589D01*
G01X-1032244Y-128674D01*
X-1031170Y-127600D01*
X-1009947D01*
X-1004010Y-133537D01*
Y-136756D01*
X-1008864D01*
Y-138800D01*
G03Y-141200I2250J-1200D01*
G01Y-144312D01*
G03Y-146712I2250J-1200D01*
G01Y-148756D01*
X-1004010D01*
Y-153291D01*
X-1008864D01*
Y-155335D01*
G03Y-157735I2250J-1200D01*
G01Y-160847D01*
G03Y-163247I2250J-1200D01*
G01Y-165291D01*
X-1004364D01*
Y-165233D01*
G02X-1003511Y-164879I500J0D01*
G01X-1001180Y-167210D01*
G03X-999833Y-170257I2440J-742D01*
G02Y-171160I-214J-452D01*
G03X-997998Y-175904I1093J-2304D01*
G01X-996700Y-177202D01*
Y-178997D01*
X-992900Y-182797D01*
G02X-993254Y-183650I-354J-354D01*
G01X-1082650D01*
Y-177150D01*
X-1082700Y-177100D01*
X-1099500D01*
Y-162500D01*
X-1122000D01*
Y-177550D01*
X-1136550D01*
Y-183650D01*
X-1201070D01*
Y-176831D01*
X-1201058Y-176793D01*
G03Y-175807I-1522J493D01*
G01X-1201070Y-175769D01*
Y-133940D01*
X-1210830D01*
Y-134000D01*
X-1225800D01*
Y-130350D01*
X-1225810D01*
Y-130310D01*
X-1237470D01*
Y-134000D01*
X-1286000D01*
Y-103500D01*
X-1299190Y-90310D01*
G02X-1299197Y-89609I354J354D01*
G03X-1301408Y-87300I-1153J1109D01*
G01X-1302200D01*
X-1306500Y-83000D01*
X-1317160D01*
X-1321500Y-78660D01*
Y-18441D01*
X-1318400D01*
Y-20000D01*
X-1303700D01*
Y-13800D01*
X-1318400D01*
Y-15241D01*
X-1321500D01*
Y-7200D01*
X-1319558D01*
G03Y-4800I1058J1200D01*
G01X-1321500D01*
Y5153D01*
G02X-1320762Y5593I500J0D01*
G03Y8407I762J1407D01*
G02X-1321500Y8847I-238J440D01*
G01Y15855D01*
X-1309418D01*
G02X-1308961Y15152I0J-500D01*
G03X-1306039I1461J-652D01*
G02X-1305582Y15855I457J204D01*
G01X-1284418D01*
G02X-1283961Y15152I0J-500D01*
G03X-1281039I1461J-652D01*
G02X-1280582Y15855I457J204D01*
G01X-1259418D01*
G02X-1258961Y15152I0J-500D01*
G03X-1256039I1461J-652D01*
G02X-1255582Y15855I457J204D01*
G01X-1234418D01*
G02X-1233961Y15152I0J-500D01*
G03X-1231039I1461J-652D01*
G02X-1230582Y15855I457J204D01*
G01X-1209418D01*
G02X-1208961Y15152I0J-500D01*
G03X-1206039I1461J-652D01*
G02X-1205582Y15855I457J204D01*
G01X-1184418D01*
G02X-1183961Y15152I0J-500D01*
G03X-1181039I1461J-652D01*
G02X-1180582Y15855I457J204D01*
G01X-1159418D01*
G02X-1158961Y15152I0J-500D01*
G03X-1156039I1461J-652D01*
G02X-1155582Y15855I457J204D01*
G01X-1134418D01*
G02X-1133961Y15152I0J-500D01*
G03X-1131039I1461J-652D01*
G02X-1130582Y15855I457J204D01*
G01X-1109418D01*
G02X-1108961Y15152I0J-500D01*
G03X-1106039I1461J-652D01*
G02X-1105582Y15855I457J204D01*
G01X-1084418D01*
G02X-1083961Y15152I0J-500D01*
G03X-1081039I1461J-652D01*
G02X-1080582Y15855I457J204D01*
G01X-1071918D01*
G02X-1071461Y15152I0J-500D01*
G03X-1068539I1461J-652D01*
G02X-1068082Y15855I457J204D01*
G01X-1046918D01*
G02X-1046461Y15152I0J-500D01*
G03X-1043539I1461J-652D01*
G02X-1043082Y15855I457J204D01*
G01X-1021918D01*
G02X-1021461Y15152I0J-500D01*
G03X-1018539I1461J-652D01*
G02X-1018082Y15855I457J204D01*
G01X-996918D01*
G02X-996461Y15152I0J-500D01*
G03X-993539I1461J-652D01*
G02X-993082Y15855I457J204D01*
G01X-971918D01*
G02X-971461Y15152I0J-500D01*
G03X-968539I1461J-652D01*
G02X-968082Y15855I457J204D01*
G01X-946918D01*
G02X-946461Y15152I0J-500D01*
G03X-943539I1461J-652D01*
G02X-943082Y15855I457J204D01*
G01X-923918D01*
G02X-923461Y15152I0J-500D01*
G03X-920539I1461J-652D01*
G02X-920082Y15855I457J204D01*
G01X-899418D01*
G02X-898961Y15152I0J-500D01*
G03X-896039I1461J-652D01*
G02X-895582Y15855I457J204D01*
G01X-874418D01*
G02X-873961Y15152I0J-500D01*
G03X-871039I1461J-652D01*
G02X-870582Y15855I457J204D01*
G01X-849918D01*
G02X-849461Y15152I0J-500D01*
G03X-846539I1461J-652D01*
G02X-846082Y15855I457J204D01*
G01X-824418D01*
G02X-823961Y15152I0J-500D01*
G03X-821039I1461J-652D01*
G02X-820582Y15855I457J204D01*
G01X-799418D01*
G02X-798961Y15152I0J-500D01*
G03X-796039I1461J-652D01*
G02X-795582Y15855I457J204D01*
G01X-774418D01*
G02X-773961Y15152I0J-500D01*
G03X-771039I1461J-652D01*
G02X-770582Y15855I457J204D01*
G01X-749418D01*
G02X-748961Y15152I0J-500D01*
G03X-746039I1461J-652D01*
G02X-745582Y15855I457J204D01*
G01X-724418D01*
G02X-723961Y15152I0J-500D01*
G03X-721039I1461J-652D01*
G02X-720582Y15855I457J204D01*
G01X-699418D01*
G02X-698961Y15152I0J-500D01*
G03X-696039I1461J-652D01*
G02X-695582Y15855I457J204D01*
G01X-674418D01*
G02X-673961Y15152I0J-500D01*
G03X-671039I1461J-652D01*
G02X-670582Y15855I457J204D01*
G01X-646918D01*
G02X-646461Y15152I0J-500D01*
G03X-643539I1461J-652D01*
G02X-643082Y15855I457J204D01*
G01X5433D01*
G02X14044Y7244I0J-8611D01*
G01Y-135827D01*
G03X18400Y-140931I5169J0D01*
G01X18611Y-140965D01*
Y-175039D01*
G02X10000Y-183650I-8611J0D01*
G01X-95850D01*
X-98000Y-181500D01*
Y-178226D01*
X-97533Y-177759D01*
X-80600D01*
Y-178559D01*
X-76200D01*
Y-174559D01*
X-80600D01*
Y-175359D01*
X-98000D01*
Y-133000D01*
X-105500Y-125500D01*
X-124441D01*
X-127891Y-122050D01*
X-148253D01*
X-149301Y-121002D01*
X-149311Y-120916D01*
G03X-151084Y-122689I-1589J-184D01*
G01X-150998Y-122699D01*
X-150724Y-122973D01*
G02X-150901Y-123400I-177J-177D01*
G01X-152447D01*
X-152498Y-123451D01*
X-152584Y-123461D01*
G03X-151573Y-126420I184J-1589D01*
G01X-151396Y-126313D01*
X-151072Y-126675D01*
X-151773Y-127376D01*
X-162706D01*
G03Y-129776I-1058J-1200D01*
G01X-152500D01*
Y-181150D01*
X-155000Y-183650D01*
X-235666D01*
G02X-236129Y-182961I0J500D01*
G03X-236000Y-182300I-1620J661D01*
G01Y-182000D01*
X-230520D01*
Y-181250D01*
X-229612D01*
X-229363Y-181500D01*
X-213937D01*
X-213369Y-180931D01*
G03X-215019Y-178286I-1131J1131D01*
G01X-215058Y-178300D01*
X-224842D01*
X-224881Y-178286D01*
G03X-225919I-519J-1514D01*
G01X-225958Y-178300D01*
X-227200D01*
Y-178050D01*
X-230520D01*
Y-164624D01*
X-229523Y-163627D01*
G03X-229699Y-163200I-177J177D01*
G01X-238624D01*
X-240585Y-165161D01*
X-242586Y-163160D01*
X-251511D01*
G03X-251687Y-163587I0J-250D01*
G01X-250690Y-164584D01*
X-250698Y-178400D01*
X-264521D01*
X-264568Y-178380D01*
G03X-266331Y-180981I-632J-1470D01*
G01X-265712Y-181600D01*
X-250700D01*
X-250701Y-182000D01*
X-246000D01*
Y-179414D01*
X-245876Y-179291D01*
G02X-245450Y-179467I177J-177D01*
G01Y-181209D01*
X-245000D01*
Y-182209D01*
G03X-244839Y-182941I1750J0D01*
G02X-245293Y-183650I-454J-209D01*
G01X-332000D01*
Y-175626D01*
G03Y-174274I-1450J676D01*
G01Y-133500D01*
X-357541D01*
X-357605Y-133346D01*
G03X-361614Y-132288I-2409J-1004D01*
G03X-365623Y-133346I-1600J-2062D01*
G01X-365688Y-133500D01*
X-372420D01*
Y-125488D01*
G03X-374820I-1200J1058D01*
G01Y-133500D01*
X-381700D01*
Y-130243D01*
X-388021Y-123922D01*
X-388008Y-123804D01*
G03X-390264Y-125096I-1592J164D01*
G01X-390222Y-125115D01*
X-389902Y-125435D01*
X-390126Y-125659D01*
X-390190Y-125676D01*
G03X-390970Y-128278I420J-1544D01*
G01Y-133500D01*
X-408500D01*
Y-137827D01*
X-408715Y-137858D01*
G03Y-146866I644J-4504D01*
G01X-408500Y-146897D01*
Y-183420D01*
G02X-409152Y-183896I-500J0D01*
G03X-410728Y-183650I-1576J-4922D01*
G01X-583000D01*
Y-61500D01*
X-587000Y-57500D01*
X-717000D01*
X-750000Y-90500D01*
Y-179500D01*
X-754150Y-183650D01*
X-968646D01*
G02X-969000Y-182797I0J500D01*
G01X-962962Y-176759D01*
X-950700D01*
Y-177559D01*
X-946300D01*
Y-173559D01*
X-950700D01*
Y-174359D01*
X-963956D01*
X-971197Y-181600D01*
X-972868D01*
Y-179783D01*
G03Y-177383I-2250J1200D01*
G01Y-174271D01*
G03Y-171871I-2250J1200D01*
G01Y-169827D01*
X-977368D01*
Y-171871D01*
G03Y-174271I2250J-1200D01*
G01Y-177383D01*
G03Y-179783I2250J-1200D01*
G01Y-181600D01*
G37*
G36*
G01X-1245160Y-155010D02*
Y-162760D01*
X-1246560D01*
Y-155090D01*
X-1247700Y-153950D01*
Y-152900D01*
X-1246800Y-152000D01*
X-1244900D01*
Y-154750D01*
X-1245160Y-155010D01*
G37*
G36*
G01X-1117079Y-181000D02*
X-1119779D01*
X-1119769Y-164160D01*
X-1113079D01*
X-1111839Y-165400D01*
Y-175490D01*
X-1116099D01*
X-1116079Y-178000D01*
X-1117079Y-179000D01*
Y-181000D01*
G37*
G36*
G01X-1104579D02*
Y-178000D01*
X-1107079Y-175500D01*
X-1109529Y-175530D01*
Y-165440D01*
X-1108289Y-164200D01*
X-1101599D01*
Y-181000D01*
X-1104579D01*
G37*
G36*
G01X-893782Y-186850D02*
X-903782D01*
Y-184850D01*
X-893782D01*
Y-186850D01*
G37*
G36*
G01X-635947Y-154401D02*
G02X-668697Y-159531I-16691J-550D01*
G01Y-150370D01*
G02X-643833Y-140760I16060J-4581D01*
G01X-638448Y-146145D01*
G02X-636050Y-153018I-14190J-8805D01*
G01Y-154298D01*
X-635947Y-154401D01*
G37*
G36*
G01X-247000Y-181000D02*
X-249700D01*
X-249690Y-164160D01*
X-243000D01*
X-241760Y-165400D01*
Y-175490D01*
X-246020D01*
X-246000Y-178000D01*
X-247000Y-179000D01*
Y-181000D01*
G37*
G36*
G01X-234500D02*
Y-178000D01*
X-237000Y-175500D01*
X-239450Y-175530D01*
Y-165440D01*
X-238210Y-164200D01*
X-231520D01*
Y-181000D01*
X-234500D01*
G37*
%LPC*%
G75*
G36*
G01X-1334500Y-12900D02*
Y-19100D01*
X-1349200D01*
Y-17641D01*
X-1354300D01*
Y-18041D01*
X-1358700D01*
Y-14041D01*
X-1354300D01*
Y-14441D01*
X-1349200D01*
Y-12900D01*
X-1334500D01*
G37*
G36*
G01X-1354900Y-26063D02*
X-1355569Y-26731D01*
G02X-1358127Y-24876I-1131J1131D01*
G01X-1358100Y-24823D01*
Y-23159D01*
X-1358700D01*
Y-19159D01*
X-1354300D01*
Y-23159D01*
X-1354900D01*
Y-26063D01*
G37*
G36*
G01X-1347998Y-116208D02*
G02X-1347689Y-120301I-8891J-2729D01*
G02X-1347998Y-116208I-9199J1364D01*
G37*
G36*
G01X-1393900Y-129550D02*
Y-133550D01*
X-1398300D01*
Y-133150D01*
X-1400100D01*
G02Y-129950I0J1600D01*
G01X-1398300D01*
Y-129550D01*
X-1393900D01*
G37*
G36*
G01X-1389700Y-134800D02*
Y-134950D01*
X-1392900D01*
Y-131450D01*
X-1389700D01*
Y-131600D01*
X-1387300D01*
G02Y-134800I0J-1600D01*
G01X-1389700D01*
G37*
G36*
G01X-1411260Y-134010D02*
Y-145669D01*
G02X-1434882I-11811J0D01*
G01Y-134010D01*
G02X-1411260I11811J11963D01*
G37*
G36*
G01X-1347998Y-169894D02*
G02X-1360173Y-158465I-8891J2729D01*
G03X-1360221Y-157514I-177J468D01*
G02X-1353556I3333J12514D01*
G03X-1353604Y-158465I129J-483D01*
G02X-1347998Y-164437I-3285J-8701D01*
G02Y-169894I-8891J-2729D01*
G37*
G36*
G01X-1450413Y-73798D02*
G02X-1451378Y-72526I-1587J-202D01*
G03X-1450687Y-72002I194J461D01*
G02X-1450693Y-71655I1587J202D01*
G03X-1451336Y-71131I-498J45D01*
G02X-1451114Y-68154I-464J1531D01*
G03X-1450400Y-67702I214J452D01*
G02X-1450399Y-67655I1600J2D01*
G03X-1451090Y-67179I-500J14D01*
G02X-1451090Y-64221I-610J1479D01*
G03X-1450400Y-63768I191J462D01*
G02X-1450366Y-63473I1600J-32D01*
G03X-1450731Y-63203I-245J51D01*
G02X-1450966Y-60292I-769J1403D01*
G03X-1450299Y-59840I167J471D01*
G02X-1449234Y-61408I1599J-60D01*
G03X-1449901Y-61860I-167J-471D01*
G02X-1449934Y-62127I-1599J61D01*
G03X-1449569Y-62397I245J-51D01*
G02X-1449410Y-65279I769J-1403D01*
G03X-1450100Y-65732I-191J-462D01*
G02X-1450101Y-65745I-1600J31D01*
G03X-1449410Y-66221I500J-14D01*
G02X-1449486Y-69146I610J-1479D01*
G03X-1450200Y-69598I-214J-452D01*
G02X-1450207Y-69745I-1600J-2D01*
G03X-1449564Y-70269I498J-45D01*
G02X-1449722Y-73274I464J-1531D01*
G03X-1450413Y-73798I-194J-461D01*
G37*
G36*
G01X-1450500Y-82159D02*
G02X-1451338Y-80793I-1599J-41D01*
G03X-1450600Y-80341I238J440D01*
G02X-1450592Y-80142I1599J41D01*
G03X-1451306Y-79642I-498J49D01*
G02X-1450408Y-78358I-694J1442D01*
G03X-1449694Y-78858I498J-49D01*
G02X-1449762Y-81707I694J-1442D01*
G03X-1450500Y-82159I-238J-440D01*
G37*
G36*
G01X-1315527Y-144838D02*
G02X-1317420Y-147362I3519J-4611D01*
G03X-1318127Y-146743I-467J180D01*
G02X-1323469Y-142869I-1756J3200D01*
G03X-1323750Y-142576I-246J46D01*
G02X-1323888I-69J495D01*
G03X-1324169Y-142869I-35J-248D01*
G02X-1327082Y-139956I-3587J-674D01*
G03X-1326788Y-139676I46J246D01*
G02Y-139537I495J69D01*
G03X-1327082Y-139257I-248J35D01*
G02X-1326796Y-132148I-674J3587D01*
G03X-1326193Y-131830I131J482D01*
G02X-1326179Y-131795I472J-165D01*
G01X-1326158Y-131747D01*
Y-131445D01*
X-1331406D01*
Y-124145D01*
X-1324106D01*
Y-128832D01*
G03X-1323581Y-129331I500J0D01*
G02X-1323562Y-129330I25J-499D01*
G01X-1323328Y-128998D01*
G02X-1320556Y-131383I3446J1203D01*
G03X-1320850Y-131663I-46J-246D01*
G02Y-131802I-495J-69D01*
G03X-1320556Y-132082I248J-35D01*
G02X-1320556Y-139257I674J-3587D01*
G03X-1320850Y-139537I-46J-246D01*
G02Y-139676I-495J-69D01*
G03X-1320556Y-139956I248J-35D01*
G02X-1316318Y-144333I674J-3587D01*
G03X-1315527Y-144838I488J-108D01*
G37*
G36*
G01X-1324169Y-174365D02*
G02X-1327082Y-171452I-3587J-674D01*
G03X-1326788Y-171172I46J246D01*
G02Y-171033I495J69D01*
G03X-1327082Y-170753I-248J35D01*
G02X-1327082Y-163578I-674J3587D01*
G03X-1326788Y-163298I46J246D01*
G02Y-163159I495J69D01*
G03X-1327082Y-162879I-248J35D01*
G02X-1324169Y-159965I-674J3587D01*
G03X-1323888Y-160259I246J-46D01*
G02X-1323750I69J-495D01*
G03X-1323469Y-159965I35J248D01*
G02X-1320556Y-162879I3587J674D01*
G03X-1320850Y-163159I-46J-246D01*
G02Y-163298I-495J-69D01*
G03X-1320556Y-163578I248J-35D01*
G02X-1320556Y-170753I674J-3587D01*
G03X-1320850Y-171033I-46J-246D01*
G02Y-171172I-495J-69D01*
G03X-1320556Y-171452I248J-35D01*
G02X-1323469Y-174365I674J-3587D01*
G03X-1323750Y-174072I-246J46D01*
G02X-1323888I-69J495D01*
G03X-1324169Y-174365I-35J-248D01*
G37*
G36*
G01X-91936Y-46914D02*
X-91920Y-46889D01*
X-91600Y-45958D01*
X-91020Y-45688D01*
G03X-91156Y-44741I-211J453D01*
G02X-83889Y-30498I1195J8365D01*
G02X-84008Y-42373I-6071J-5877D01*
G02X-88932Y-44763I-5953J5997D01*
G03X-89046Y-45725I65J-496D01*
G01X-87619Y-46273D01*
X-86454Y-48771D01*
X-86773Y-49787D01*
X-90342Y-51451D01*
X-91325Y-51043D01*
X-92490Y-48545D01*
X-92304Y-48003D01*
X-92301Y-47973D01*
G02X-91936Y-46914I2340J-213D01*
G37*
G36*
G01X-135244D02*
X-135227Y-46889D01*
X-134907Y-45958D01*
X-134327Y-45688D01*
G03X-134463Y-44741I-211J453D01*
G02X-127197Y-30498I1195J8365D01*
G02X-127315Y-42373I-6071J-5877D01*
G02X-132239Y-44763I-5953J5997D01*
G03X-132353Y-45725I65J-496D01*
G01X-130926Y-46273D01*
X-129761Y-48771D01*
X-130080Y-49787D01*
X-133649Y-51451D01*
X-134632Y-51043D01*
X-135797Y-48545D01*
X-135611Y-48003D01*
X-135608Y-47973D01*
G02X-135244Y-46914I2340J-213D01*
G37*
G36*
G01X-962015D02*
X-961999Y-46889D01*
X-961679Y-45958D01*
X-961099Y-45688D01*
G03X-961235Y-44741I-211J453D01*
G02X-953921Y-30548I1195J8365D01*
G02X-954078Y-42365I-6119J-5828D01*
G02X-959010Y-44763I-5961J5989D01*
G03X-959125Y-45725I65J-496D01*
G01X-957697Y-46273D01*
X-956533Y-48771D01*
X-956852Y-49787D01*
X-960420Y-51451D01*
X-961404Y-51043D01*
X-962569Y-48545D01*
X-962382Y-48003D01*
X-962380Y-47973D01*
G02X-962015Y-46914I2340J-213D01*
G37*
G36*
G01X-1005322D02*
X-1005306Y-46889D01*
X-1004986Y-45958D01*
X-1004406Y-45688D01*
G03X-1004542Y-44741I-211J453D01*
G02X-997228Y-30548I1195J8365D01*
G02X-997385Y-42365I-6119J-5828D01*
G02X-1002317Y-44763I-5961J5989D01*
G03X-1002432Y-45725I65J-496D01*
G01X-1001004Y-46273D01*
X-999840Y-48771D01*
X-1000159Y-49787D01*
X-1003727Y-51451D01*
X-1004711Y-51043D01*
X-1005876Y-48545D01*
X-1005690Y-48003D01*
X-1005687Y-47973D01*
G02X-1005322Y-46914I2340J-213D01*
G37*
G36*
G01X-1191500Y1750D02*
X-1189359D01*
Y2200D01*
X-1185359D01*
Y-2200D01*
X-1189359D01*
Y-1750D01*
X-1191500D01*
G02Y1750I0J1750D01*
G37*
G36*
G01X-321859Y100D02*
X-319859D01*
Y700D01*
X-315859D01*
Y-3700D01*
X-319859D01*
Y-3100D01*
X-321859D01*
G02Y100I0J1600D01*
G37*
G36*
G01X-291236Y-5698D02*
X-291302Y-5650D01*
X-291869D01*
Y-6650D01*
X-295869D01*
Y-2250D01*
X-291869D01*
Y-3250D01*
X-291417D01*
X-291346Y-3190D01*
G02X-291236Y-5698I1046J-1210D01*
G37*
G36*
G01X-302300Y-2700D02*
X-300987D01*
Y-2250D01*
X-296987D01*
Y-6650D01*
X-300987D01*
Y-6200D01*
X-302300D01*
G02Y-2700I0J1750D01*
G37*
G36*
G01X-1160694Y-7004D02*
X-1160762Y-6950D01*
X-1161369D01*
Y-7650D01*
X-1165369D01*
Y-3250D01*
X-1161369D01*
Y-4550D01*
X-1160762D01*
X-1160694Y-4496D01*
G02Y-7004I994J-1254D01*
G37*
G36*
G01X-1171710Y-3694D02*
X-1171682Y-3700D01*
X-1170487D01*
Y-3250D01*
X-1166487D01*
Y-7650D01*
X-1170487D01*
Y-7200D01*
X-1172774D01*
X-1173337Y-6637D01*
G02X-1171710Y-3694I1237J1237D01*
G37*
G36*
G01X-1179794Y-7054D02*
X-1179862Y-7000D01*
X-1180241D01*
Y-8000D01*
X-1184241D01*
Y-3600D01*
X-1183441D01*
Y-2200D01*
X-1184241D01*
Y2200D01*
X-1180241D01*
Y-2200D01*
X-1181041D01*
Y-3600D01*
X-1180241D01*
Y-4600D01*
X-1179862D01*
X-1179794Y-4546D01*
G02Y-7054I994J-1254D01*
G37*
G36*
G01X-1191301Y-4600D02*
X-1189359D01*
Y-3600D01*
X-1185359D01*
Y-8000D01*
X-1189359D01*
Y-7000D01*
X-1191301D01*
G02Y-4600I-1058J1200D01*
G37*
G36*
G01X-449762Y-4800D02*
G02X-449533Y-7200I1162J-1100D01*
G01X-452921D01*
Y-9100D01*
X-467621D01*
Y-2900D01*
X-452921D01*
Y-4800D01*
X-449762D01*
G37*
G36*
G01X-309733Y-6100D02*
G02X-309962Y-8500I933J-1300D01*
G01X-310741D01*
Y-9500D01*
X-314741D01*
Y-5100D01*
X-313941D01*
Y-3700D01*
X-314741D01*
Y700D01*
X-310741D01*
Y-3700D01*
X-311541D01*
Y-5100D01*
X-310741D01*
Y-6100D01*
X-309733D01*
G37*
G36*
G01X-320742D02*
X-319859D01*
Y-5100D01*
X-315859D01*
Y-9500D01*
X-319859D01*
Y-8500D01*
X-320742D01*
G02Y-6100I-1058J1200D01*
G37*
G36*
G01X-290700Y-8000D02*
G02Y-11500I0J-1750D01*
G01X-292013D01*
Y-11950D01*
X-296013D01*
Y-7550D01*
X-292013D01*
Y-8000D01*
X-290700D01*
G37*
G36*
G01X-170500Y-8400D02*
G02Y-11600I0J-1600D01*
G01X-171941D01*
Y-12200D01*
X-175941D01*
Y-7800D01*
X-171941D01*
Y-8400D01*
X-170500D01*
G37*
G36*
G01X-1041846Y-11763D02*
X-1041884Y-11750D01*
X-1043441D01*
Y-12200D01*
X-1047441D01*
Y-7800D01*
X-1043441D01*
Y-8250D01*
X-1040675D01*
X-1040063Y-8863D01*
G02X-1041846Y-11763I-1237J-1237D01*
G37*
G36*
G01X-180561Y1761D02*
Y2600D01*
X-180411D01*
Y3723D01*
X-180438Y3776D01*
G02X-177880Y5631I1427J724D01*
G01X-177211Y4963D01*
Y2600D01*
X-173439D01*
Y-600D01*
X-173600D01*
Y-1242D01*
X-173586Y-1281D01*
G02Y-2319I-1514J-519D01*
G01X-173600Y-2358D01*
Y-2900D01*
X-173450D01*
Y-6100D01*
X-176971D01*
Y-6836D01*
X-176471Y-7336D01*
Y-12600D01*
X-182735D01*
X-183485Y-11850D01*
X-193921D01*
Y1350D01*
X-181346D01*
G03X-180561Y1761I285J411D01*
G37*
G36*
G01X-1052561Y532D02*
Y2600D01*
G02X-1049061I1750J0D01*
G01Y1600D01*
X-1047900D01*
X-1047854Y1619D01*
G02X-1046524I665J-1619D01*
G01X-1046478Y1600D01*
X-1045439D01*
Y-3314D01*
X-1045450Y-3325D01*
Y-7000D01*
X-1046489D01*
X-1046535Y-7019D01*
G02X-1047472Y-7129I-665J1619D01*
G03X-1048050Y-7623I-78J-494D01*
G01Y-12600D01*
X-1054314D01*
X-1055064Y-11850D01*
X-1064414D01*
X-1065500Y-10764D01*
Y-86D01*
X-1064064Y1350D01*
X-1054586D01*
X-1053415Y179D01*
G03X-1052561Y532I354J354D01*
G37*
G36*
G01X-1178890Y-10928D02*
G02X-1178825Y-13328I1090J-1172D01*
G01X-1180291D01*
Y-14328D01*
X-1184291D01*
Y-9928D01*
X-1180291D01*
Y-10928D01*
X-1178890D01*
G37*
G36*
G01X-1191200Y-10378D02*
X-1189409D01*
Y-9928D01*
X-1185409D01*
Y-14328D01*
X-1189409D01*
Y-13878D01*
X-1191200D01*
G02Y-10378I0J1750D01*
G37*
G36*
G01X-1296600Y-12342D02*
Y-10000D01*
X-1306900D01*
Y-3800D01*
X-1292200D01*
Y-10000D01*
X-1294200D01*
Y-12342D01*
G02X-1296600I-1200J-1058D01*
G37*
G36*
G01X-308958Y-12428D02*
G02Y-14828I1058J-1200D01*
G01X-310791D01*
Y-15828D01*
X-314791D01*
Y-11428D01*
X-310791D01*
Y-12428D01*
X-308958D01*
G37*
G36*
G01X-321700Y-11878D02*
X-319909D01*
Y-11428D01*
X-315909D01*
Y-15828D01*
X-319909D01*
Y-15378D01*
X-321700D01*
G02Y-11878I0J1750D01*
G37*
G36*
G01X-425700Y-13238D02*
Y-10000D01*
X-436821D01*
Y-3800D01*
X-422121D01*
Y-10000D01*
X-423300D01*
Y-13467D01*
G02X-425700Y-13238I-1300J-933D01*
G37*
G36*
G01X-301838Y-13743D02*
G03X-301131Y-13288I207J455D01*
G01Y-13050D01*
X-300331D01*
Y-11950D01*
X-301131D01*
Y-7550D01*
X-297131D01*
Y-11950D01*
X-297931D01*
Y-13050D01*
X-297131D01*
Y-17450D01*
X-301131D01*
Y-16450D01*
X-301497D01*
X-301563Y-16497D01*
G02X-301838Y-13743I-937J1297D01*
G37*
G36*
G01X-1159758Y-15050D02*
G02Y-17450I1058J-1200D01*
G01X-1161369D01*
Y-18450D01*
X-1165369D01*
Y-14050D01*
X-1164569D01*
Y-12950D01*
X-1165369D01*
Y-8550D01*
X-1161369D01*
Y-12950D01*
X-1162169D01*
Y-14050D01*
X-1161369D01*
Y-15050D01*
X-1159758D01*
G37*
G36*
G01X-1171800Y-14500D02*
X-1170487D01*
Y-14050D01*
X-1166487D01*
Y-18450D01*
X-1170487D01*
Y-18000D01*
X-1171800D01*
G02Y-14500I0J1750D01*
G37*
G36*
G01X-170300Y-14900D02*
G02Y-18100I0J-1600D01*
G01X-171750D01*
Y-18700D01*
X-175750D01*
Y-14300D01*
X-171750D01*
Y-14900D01*
X-170300D01*
G37*
G36*
G01X-1040063Y-17737D02*
X-1040675Y-18350D01*
X-1043550D01*
Y-18800D01*
X-1047550D01*
Y-14400D01*
X-1043550D01*
Y-14850D01*
X-1041884D01*
X-1041846Y-14837D01*
G02X-1040063Y-17737I546J-1663D01*
G37*
G36*
G01X-448321Y-15241D02*
Y-13800D01*
X-433621D01*
Y-20000D01*
X-448321D01*
Y-18441D01*
X-452221D01*
Y-18841D01*
X-456621D01*
Y-14841D01*
X-452221D01*
Y-15241D01*
X-448321D01*
G37*
G36*
G01X-1179944Y-24504D02*
X-1180012Y-24450D01*
X-1180369D01*
Y-25650D01*
X-1184369D01*
Y-21250D01*
X-1183569D01*
Y-20450D01*
X-1184369D01*
Y-16050D01*
X-1180369D01*
Y-20450D01*
X-1181169D01*
Y-21250D01*
X-1180369D01*
Y-22050D01*
X-1180012D01*
X-1179944Y-21996D01*
G02Y-24504I994J-1254D01*
G37*
G36*
G01X-1190800Y-21700D02*
X-1189487D01*
Y-21250D01*
X-1185487D01*
Y-25650D01*
X-1189487D01*
Y-25200D01*
X-1190800D01*
G02Y-21700I0J1750D01*
G37*
G36*
G01X-310394Y-26354D02*
X-310462Y-26300D01*
X-310869D01*
Y-27150D01*
X-314869D01*
Y-22750D01*
X-314069D01*
Y-21950D01*
X-314869D01*
Y-17550D01*
X-310869D01*
Y-21950D01*
X-311669D01*
Y-22750D01*
X-310869D01*
Y-23900D01*
X-310462D01*
X-310394Y-23846D01*
G02Y-26354I994J-1254D01*
G37*
G36*
G01X-321300Y-23200D02*
X-319987D01*
Y-22750D01*
X-315987D01*
Y-27150D01*
X-319987D01*
Y-26700D01*
X-321300D01*
G02Y-23200I0J1750D01*
G37*
G36*
G01X-291869Y-28021D02*
Y-28150D01*
X-295869D01*
Y-23750D01*
X-295069D01*
Y-22950D01*
X-295869D01*
Y-18550D01*
X-291869D01*
Y-22950D01*
X-292669D01*
Y-23750D01*
X-291869D01*
Y-23979D01*
G03X-291234Y-24460I500J0D01*
G02Y-27540I434J-1540D01*
G03X-291869Y-28021I-136J-481D01*
G37*
G36*
G01X-302300Y-24200D02*
X-300987D01*
Y-23750D01*
X-296987D01*
Y-28150D01*
X-300987D01*
Y-27700D01*
X-302300D01*
G02Y-24200I0J1750D01*
G37*
G36*
G01X-1161369Y-28723D02*
Y-29150D01*
X-1165369D01*
Y-24750D01*
X-1164569D01*
Y-23950D01*
X-1165369D01*
Y-19550D01*
X-1161369D01*
Y-23950D01*
X-1162169D01*
Y-24750D01*
X-1161369D01*
Y-24777D01*
G03X-1160698Y-25247I500J0D01*
G02Y-28254I548J-1503D01*
G03X-1161369Y-28723I-171J-470D01*
G37*
G36*
G01X-1171800Y-25200D02*
X-1170487D01*
Y-24750D01*
X-1166487D01*
Y-29150D01*
X-1170487D01*
Y-28700D01*
X-1171800D01*
G02Y-25200I0J1750D01*
G37*
G36*
G01X-1193137Y-28263D02*
X-1192525Y-27650D01*
X-1189359D01*
Y-27200D01*
X-1185359D01*
Y-31600D01*
X-1189359D01*
Y-31150D01*
X-1191316D01*
X-1191354Y-31163D01*
G02X-1193137Y-28263I-546J1663D01*
G37*
G36*
G01X-1310206Y-28946D02*
X-1310138Y-29000D01*
X-1309559D01*
Y-28000D01*
X-1305559D01*
Y-32400D01*
X-1309559D01*
Y-31400D01*
X-1310138D01*
X-1310206Y-31454D01*
G02Y-28946I-994J1254D01*
G37*
G36*
G01X-323637Y-29763D02*
X-323025Y-29150D01*
X-319859D01*
Y-28700D01*
X-315859D01*
Y-33100D01*
X-319859D01*
Y-32650D01*
X-321816D01*
X-321854Y-32663D01*
G02X-323637Y-29763I-546J1663D01*
G37*
G36*
G01X-1160346Y-34763D02*
X-1160384Y-34750D01*
X-1161441D01*
Y-35200D01*
X-1165441D01*
Y-30800D01*
X-1161441D01*
Y-31250D01*
X-1159175D01*
X-1158563Y-31863D01*
G02X-1160346Y-34763I-1237J-1237D01*
G37*
G36*
G01X-1052858Y-25031D02*
G02X-1052661Y-24787I1458J-969D01*
G01Y-21400D01*
X-1051622D01*
X-1051576Y-21381D01*
G02X-1050246I665J-1619D01*
G01X-1050200Y-21400D01*
X-1045539D01*
Y-24600D01*
X-1045689D01*
Y-25637D01*
X-1045600Y-25726D01*
Y-27800D01*
X-1045450D01*
Y-31000D01*
X-1048150D01*
Y-36600D01*
X-1054414D01*
X-1055164Y-35850D01*
X-1064414D01*
X-1065600Y-34664D01*
Y-23836D01*
X-1064414Y-22650D01*
X-1056086D01*
X-1053628Y-25108D01*
G03X-1052858Y-25031I354J354D01*
G37*
G36*
G01X-170200Y-32870D02*
G02Y-36070I0J-1600D01*
G01X-171841D01*
Y-36670D01*
X-175841D01*
Y-32270D01*
X-171841D01*
Y-32870D01*
X-170200D01*
G37*
G36*
G01X-178211Y-21300D02*
Y-22900D01*
X-174639D01*
Y-26100D01*
X-174789D01*
Y-26846D01*
X-174784Y-26872D01*
G02X-174750Y-27200I-1566J-328D01*
G01Y-28250D01*
X-174600D01*
Y-31450D01*
X-176520D01*
X-176648Y-31759D01*
X-176571Y-31836D01*
Y-37100D01*
X-182835D01*
X-183585Y-36350D01*
X-194021D01*
Y-23150D01*
X-181907D01*
X-181657Y-22900D01*
X-181411D01*
Y-21300D01*
G02X-178211I1600J0D01*
G37*
G36*
G01X-1179517Y-33370D02*
G02X-1179673Y-36141I717J-1430D01*
G01X-1179736Y-36100D01*
X-1180241D01*
Y-37100D01*
X-1184241D01*
Y-32700D01*
X-1183441D01*
Y-31600D01*
X-1184241D01*
Y-27200D01*
X-1180241D01*
Y-31600D01*
X-1181041D01*
Y-32700D01*
X-1180241D01*
Y-32923D01*
G03X-1179517Y-33370I500J0D01*
G37*
G36*
G01X-431394Y-36854D02*
X-431462Y-36800D01*
X-431841D01*
Y-37800D01*
X-435841D01*
Y-33400D01*
X-435041D01*
Y-31700D01*
X-435841D01*
Y-27300D01*
X-431841D01*
Y-31700D01*
X-432641D01*
Y-33400D01*
X-431841D01*
Y-34400D01*
X-431462D01*
X-431394Y-34346D01*
G02Y-36854I994J-1254D01*
G37*
G36*
G01X-441959Y-33850D02*
X-440959D01*
Y-33400D01*
X-436959D01*
Y-37800D01*
X-440959D01*
Y-37350D01*
X-441959D01*
G02Y-33850I0J1750D01*
G37*
G36*
G01X-1299694Y-36954D02*
X-1299762Y-36900D01*
X-1300441D01*
Y-37900D01*
X-1304441D01*
Y-33500D01*
X-1300441D01*
Y-34500D01*
X-1299762D01*
X-1299694Y-34446D01*
G02Y-36954I994J-1254D01*
G37*
G36*
G01X-1310559Y-33950D02*
X-1309559D01*
Y-33500D01*
X-1305559D01*
Y-37900D01*
X-1309559D01*
Y-37450D01*
X-1310559D01*
G02Y-33950I0J1750D01*
G37*
G36*
G01X-309558Y-35200D02*
G02Y-37600I1058J-1200D01*
G01X-310741D01*
Y-38600D01*
X-314741D01*
Y-34200D01*
X-313941D01*
Y-33100D01*
X-314741D01*
Y-28700D01*
X-310741D01*
Y-33100D01*
X-311541D01*
Y-34200D01*
X-310741D01*
Y-35200D01*
X-309558D01*
G37*
G36*
G01X-1046637Y-39237D02*
X-1047191Y-38684D01*
Y-36346D01*
X-1047441Y-36096D01*
Y-31800D01*
X-1043441D01*
Y-36200D01*
X-1043691Y-36450D01*
Y-37623D01*
X-1043686Y-37648D01*
G02X-1046637Y-39237I-1714J-352D01*
G37*
G36*
G01X-290558Y-33700D02*
X-292141D01*
Y-34700D01*
X-292941D01*
Y-35800D01*
X-292141D01*
Y-40200D01*
X-296141D01*
Y-35800D01*
X-295341D01*
Y-34700D01*
X-296141D01*
Y-30300D01*
X-292141D01*
Y-31300D01*
X-290558D01*
G02Y-33700I1058J-1200D01*
G37*
G36*
G01X-302354Y-36237D02*
X-302316Y-36250D01*
X-301259D01*
Y-35800D01*
X-297259D01*
Y-40200D01*
X-301259D01*
Y-39750D01*
X-303525D01*
X-304137Y-39137D01*
G02X-302354Y-36237I1237J1237D01*
G37*
G36*
G01X-1171442Y-37300D02*
X-1170559D01*
Y-36300D01*
X-1169759D01*
Y-35200D01*
X-1170559D01*
Y-30800D01*
X-1166559D01*
Y-35200D01*
X-1167359D01*
Y-36300D01*
X-1166559D01*
Y-40700D01*
X-1170559D01*
Y-39700D01*
X-1171442D01*
G02Y-37300I-1058J1200D01*
G37*
G36*
G01X-1191200Y-43100D02*
G02Y-37900I0J2600D01*
G01X-1187559D01*
G02X-1186231Y-38265I0J-2600D01*
G01X-1186172Y-38300D01*
X-1185559D01*
Y-38836D01*
X-1185506Y-38904D01*
G02Y-42096I-2053J-1596D01*
G01X-1185559Y-42164D01*
Y-42700D01*
X-1186172D01*
X-1186231Y-42735D01*
G02X-1187559Y-43100I-1328J2235D01*
G01X-1191200D01*
G37*
G36*
G01X-430458Y-39900D02*
G02Y-42300I1058J-1200D01*
G01X-431841D01*
Y-43300D01*
X-435841D01*
Y-38900D01*
X-431841D01*
Y-39900D01*
X-430458D01*
G37*
G36*
G01X-441959Y-39350D02*
X-440959D01*
Y-38900D01*
X-436959D01*
Y-43300D01*
X-440959D01*
Y-42850D01*
X-441959D01*
G02Y-39350I0J1750D01*
G37*
G36*
G01X-1299058Y-40000D02*
G02Y-42400I1058J-1200D01*
G01X-1300441D01*
Y-43400D01*
X-1304441D01*
Y-39000D01*
X-1300441D01*
Y-40000D01*
X-1299058D01*
G37*
G36*
G01X-1310559Y-39450D02*
X-1309559D01*
Y-39000D01*
X-1305559D01*
Y-43400D01*
X-1309559D01*
Y-42950D01*
X-1310559D01*
G02Y-39450I0J1750D01*
G37*
G36*
G01X-321700Y-44600D02*
G02Y-39400I0J2600D01*
G01X-318059D01*
G02X-316731Y-39765I0J-2600D01*
G01X-316672Y-39800D01*
X-316059D01*
Y-40336D01*
X-316006Y-40404D01*
G02Y-43596I-2053J-1596D01*
G01X-316059Y-43664D01*
Y-44200D01*
X-316672D01*
X-316731Y-44235D01*
G02X-318059Y-44600I-1328J2235D01*
G01X-321700D01*
G37*
G36*
G01X-302142Y-42100D02*
X-301259D01*
Y-41100D01*
X-297259D01*
Y-45500D01*
X-301259D01*
Y-44500D01*
X-302142D01*
G02Y-42100I-1058J1200D01*
G37*
G36*
G01X-1171442Y-42800D02*
X-1170559D01*
Y-41800D01*
X-1166559D01*
Y-46200D01*
X-1170559D01*
Y-45200D01*
X-1171442D01*
G02Y-42800I-1058J1200D01*
G37*
G36*
G01X-1180441Y-48524D02*
Y-48700D01*
X-1184441D01*
Y-44300D01*
X-1180441D01*
Y-45300D01*
X-1179677D01*
X-1179624Y-45273D01*
G02X-1179693Y-48090I724J-1427D01*
G03X-1180441Y-48524I-248J-434D01*
G37*
G36*
G01X-1190006Y-45246D02*
X-1189938Y-45300D01*
X-1189559D01*
Y-44300D01*
X-1185559D01*
Y-48700D01*
X-1189559D01*
Y-47700D01*
X-1189938D01*
X-1190006Y-47754D01*
G02Y-45246I-994J1254D01*
G37*
G36*
G01X-441806Y-45346D02*
X-441738Y-45400D01*
X-440959D01*
Y-44400D01*
X-436959D01*
Y-48800D01*
X-440959D01*
Y-47800D01*
X-441738D01*
X-441806Y-47854D01*
G02Y-45346I-994J1254D01*
G37*
G36*
G01X-310941Y-49524D02*
Y-49700D01*
X-314941D01*
Y-45300D01*
X-310941D01*
Y-46300D01*
X-310177D01*
X-310124Y-46273D01*
G02X-310193Y-49090I724J-1427D01*
G03X-310941Y-49524I-248J-434D01*
G37*
G36*
G01X-320506Y-46246D02*
X-320438Y-46300D01*
X-320059D01*
Y-45300D01*
X-316059D01*
Y-49700D01*
X-320059D01*
Y-48700D01*
X-320438D01*
X-320506Y-48754D01*
G02Y-46246I-994J1254D01*
G37*
G36*
G01X-289163Y-44437D02*
X-289775Y-45050D01*
X-292141D01*
Y-45500D01*
X-292391Y-45750D01*
Y-46454D01*
X-292141Y-46704D01*
Y-51000D01*
X-296141D01*
Y-46600D01*
X-295891Y-46350D01*
Y-45646D01*
X-296141Y-45396D01*
Y-41100D01*
X-292141D01*
Y-41550D01*
X-290984D01*
X-290946Y-41537D01*
G02X-289163Y-44437I546J-1663D01*
G37*
G36*
G01X-302142Y-47600D02*
X-301259D01*
Y-46600D01*
X-297259D01*
Y-51000D01*
X-301259D01*
Y-50000D01*
X-302142D01*
G02Y-47600I-1058J1200D01*
G37*
G36*
G01X-100795Y-46914D02*
X-100778Y-46889D01*
X-100458Y-45958D01*
X-99031Y-45293D01*
X-96477Y-46273D01*
X-95312Y-48771D01*
X-95632Y-49787D01*
X-99200Y-51451D01*
X-100184Y-51043D01*
X-101348Y-48545D01*
X-101162Y-48003D01*
X-101159Y-47973D01*
G02X-100795Y-46914I2340J-213D01*
G37*
G36*
G01X-144102D02*
X-144086Y-46889D01*
X-143765Y-45958D01*
X-142338Y-45293D01*
X-139784Y-46273D01*
X-138619Y-48771D01*
X-138939Y-49787D01*
X-142507Y-51451D01*
X-143491Y-51043D01*
X-144655Y-48545D01*
X-144469Y-48003D01*
X-144466Y-47973D01*
G02X-144102Y-46914I2340J-213D01*
G37*
G36*
G01X-970874D02*
X-970857Y-46889D01*
X-970537Y-45958D01*
X-969109Y-45293D01*
X-966556Y-46273D01*
X-965391Y-48771D01*
X-965710Y-49787D01*
X-969279Y-51451D01*
X-970262Y-51043D01*
X-971427Y-48545D01*
X-971241Y-48003D01*
X-971238Y-47973D01*
G02X-970874Y-46914I2340J-213D01*
G37*
G36*
G01X-1014181D02*
X-1014164Y-46889D01*
X-1013844Y-45958D01*
X-1012416Y-45293D01*
X-1009863Y-46273D01*
X-1008698Y-48771D01*
X-1009017Y-49787D01*
X-1012586Y-51451D01*
X-1013569Y-51043D01*
X-1014734Y-48545D01*
X-1014548Y-48003D01*
X-1014545Y-47973D01*
G02X-1014181Y-46914I2340J-213D01*
G37*
G36*
G01X-1158463Y-45137D02*
X-1159075Y-45750D01*
X-1161441D01*
Y-46200D01*
X-1161691Y-46450D01*
Y-47154D01*
X-1161441Y-47404D01*
Y-51700D01*
X-1165441D01*
Y-47300D01*
X-1165191Y-47050D01*
Y-46346D01*
X-1165441Y-46096D01*
Y-41800D01*
X-1161441D01*
Y-42250D01*
X-1160284D01*
X-1160246Y-42237D01*
G02X-1158463Y-45137I546J-1663D01*
G37*
G36*
G01X-1172142Y-48500D02*
X-1171397D01*
X-1171197Y-48300D01*
X-1170559D01*
Y-47300D01*
X-1166559D01*
Y-51700D01*
X-1170559D01*
Y-50900D01*
X-1172142D01*
G02Y-48500I-1058J1200D01*
G37*
G36*
G01X-431174Y-53354D02*
X-431242Y-53300D01*
X-431841D01*
Y-54300D01*
X-435841D01*
Y-49900D01*
X-431841D01*
Y-50900D01*
X-431242D01*
X-431174Y-50846D01*
G02Y-53354I994J-1254D01*
G37*
G36*
G01X-441959Y-50350D02*
X-440959D01*
Y-49900D01*
X-436959D01*
Y-54300D01*
X-440959D01*
Y-53850D01*
X-441959D01*
G02Y-50350I0J1750D01*
G37*
G36*
G01X-1299774Y-53454D02*
X-1299842Y-53400D01*
X-1300441D01*
Y-54400D01*
X-1304441D01*
Y-50000D01*
X-1303641D01*
Y-48900D01*
X-1304441D01*
Y-44500D01*
X-1300441D01*
Y-48900D01*
X-1301241D01*
Y-50000D01*
X-1300441D01*
Y-51000D01*
X-1299842D01*
X-1299774Y-50946D01*
G02Y-53454I994J-1254D01*
G37*
G36*
G01X-1310559Y-50450D02*
X-1309559D01*
Y-50000D01*
X-1305559D01*
Y-54400D01*
X-1309559D01*
Y-53950D01*
X-1310559D01*
G02Y-50450I0J1750D01*
G37*
G36*
G01X-85034Y-54974D02*
X-85052Y-55002D01*
X-85296Y-55766D01*
X-86708Y-56464D01*
X-89283Y-55541D01*
X-90504Y-53070D01*
X-90207Y-52047D01*
X-86678Y-50303D01*
X-85685Y-50689D01*
X-84464Y-53160D01*
X-84659Y-53769D01*
X-84660Y-53802D01*
G02X-85034Y-54974I-2348J104D01*
G37*
G36*
G01X-93892D02*
X-93910Y-55002D01*
X-94154Y-55766D01*
X-95566Y-56464D01*
X-98142Y-55541D01*
X-99362Y-53070D01*
X-99066Y-52047D01*
X-95536Y-50303D01*
X-94543Y-50689D01*
X-93323Y-53160D01*
X-93517Y-53769D01*
X-93518Y-53802D01*
G02X-93892Y-54974I-2348J104D01*
G37*
G36*
G01X-128341Y-54974D02*
X-128359Y-55002D01*
X-128603Y-55766D01*
X-130015Y-56464D01*
X-132590Y-55541D01*
X-133811Y-53070D01*
X-133515Y-52047D01*
X-129985Y-50303D01*
X-128992Y-50689D01*
X-127771Y-53160D01*
X-127966Y-53769D01*
X-127967Y-53802D01*
G02X-128341Y-54974I-2348J104D01*
G37*
G36*
G01X-137199D02*
X-137217Y-55002D01*
X-137461Y-55766D01*
X-138874Y-56464D01*
X-141449Y-55541D01*
X-142669Y-53070D01*
X-142373Y-52047D01*
X-138843Y-50303D01*
X-137850Y-50689D01*
X-136630Y-53160D01*
X-136824Y-53769D01*
X-136826Y-53802D01*
G02X-137199Y-54974I-2348J104D01*
G37*
G36*
G01X-955113Y-54974D02*
X-955131Y-55002D01*
X-955375Y-55766D01*
X-956787Y-56464D01*
X-959362Y-55541D01*
X-960583Y-53070D01*
X-960286Y-52047D01*
X-956756Y-50303D01*
X-955764Y-50689D01*
X-954543Y-53160D01*
X-954737Y-53769D01*
X-954739Y-53802D01*
G02X-955113Y-54974I-2348J104D01*
G37*
G36*
G01X-963971D02*
X-963989Y-55002D01*
X-964233Y-55766D01*
X-965645Y-56464D01*
X-968220Y-55541D01*
X-969441Y-53070D01*
X-969144Y-52047D01*
X-965615Y-50303D01*
X-964622Y-50689D01*
X-963401Y-53160D01*
X-963596Y-53769D01*
X-963597Y-53802D01*
G02X-963971Y-54974I-2348J104D01*
G37*
G36*
G01X-998420Y-54974D02*
X-998438Y-55002D01*
X-998682Y-55766D01*
X-1000094Y-56464D01*
X-1002669Y-55541D01*
X-1003890Y-53070D01*
X-1003593Y-52047D01*
X-1000064Y-50303D01*
X-999071Y-50689D01*
X-997850Y-53160D01*
X-998045Y-53769D01*
X-998046Y-53802D01*
G02X-998420Y-54974I-2348J104D01*
G37*
G36*
G01X-1007278D02*
X-1007296Y-55002D01*
X-1007540Y-55766D01*
X-1008952Y-56464D01*
X-1011527Y-55541D01*
X-1012748Y-53070D01*
X-1012452Y-52047D01*
X-1008922Y-50303D01*
X-1007929Y-50689D01*
X-1006708Y-53160D01*
X-1006903Y-53769D01*
X-1006904Y-53802D01*
G02X-1007278Y-54974I-2348J104D01*
G37*
G36*
G01X-430058Y-56400D02*
G02Y-58800I1058J-1200D01*
G01X-431841D01*
Y-59800D01*
X-435841D01*
Y-55400D01*
X-431841D01*
Y-56400D01*
X-430058D01*
G37*
G36*
G01X-441959Y-55850D02*
X-440959D01*
Y-55400D01*
X-436959D01*
Y-59800D01*
X-440959D01*
Y-59350D01*
X-441959D01*
G02Y-55850I0J1750D01*
G37*
G36*
G01X-1310559Y-55950D02*
X-1309559D01*
Y-55500D01*
X-1305559D01*
Y-59900D01*
X-1309559D01*
Y-59450D01*
X-1310559D01*
G02Y-55950I0J1750D01*
G37*
G36*
G01X-1299460Y-59049D02*
X-1299525Y-58900D01*
X-1300441D01*
Y-59900D01*
X-1304441D01*
Y-55500D01*
X-1300441D01*
Y-56500D01*
X-1298203D01*
X-1297898Y-56805D01*
X-1297811Y-56815D01*
G02X-1299460Y-59049I-184J-1589D01*
G37*
G36*
G01X-431841Y-65100D02*
Y-65300D01*
X-435841D01*
Y-60900D01*
X-431841D01*
Y-61100D01*
G03X-431188Y-61576I500J0D01*
G02Y-64624I488J-1524D01*
G03X-431841Y-65100I-153J-476D01*
G37*
G36*
G01X-441959Y-61350D02*
X-440959D01*
Y-60900D01*
X-436959D01*
Y-65300D01*
X-440959D01*
Y-64850D01*
X-441959D01*
G02Y-61350I0J1750D01*
G37*
G36*
G01X-1299458Y-62000D02*
G02Y-64400I1058J-1200D01*
G01X-1300441D01*
Y-65400D01*
X-1304441D01*
Y-61000D01*
X-1300441D01*
Y-62000D01*
X-1299458D01*
G37*
G36*
G01X-1310559Y-61450D02*
X-1309559D01*
Y-61000D01*
X-1305559D01*
Y-65400D01*
X-1309559D01*
Y-64950D01*
X-1310559D01*
G02Y-61450I0J1750D01*
G37*
G36*
G01X-447350Y-60841D02*
Y-61841D01*
X-446900D01*
Y-65841D01*
X-451300D01*
Y-61841D01*
X-450850D01*
Y-60841D01*
G02X-447350I1750J0D01*
G37*
G36*
G01X-1316446Y-61194D02*
X-1316500Y-61262D01*
Y-61941D01*
X-1315500D01*
Y-65941D01*
X-1319900D01*
Y-61941D01*
X-1318900D01*
Y-61262D01*
X-1318954Y-61194D01*
G02X-1316446I1254J994D01*
G37*
G36*
G01X-91936Y-61875D02*
X-91920Y-61850D01*
X-91600Y-60919D01*
X-90172Y-60253D01*
X-87619Y-61234D01*
X-86454Y-63732D01*
X-86773Y-64748D01*
X-90342Y-66412D01*
X-91325Y-66003D01*
X-92490Y-63505D01*
X-92304Y-62964D01*
X-92301Y-62934D01*
G02X-91936Y-61875I2340J-213D01*
G37*
G36*
G01X-100795D02*
X-100778Y-61850D01*
X-100458Y-60919D01*
X-99031Y-60253D01*
X-96477Y-61234D01*
X-95312Y-63732D01*
X-95632Y-64748D01*
X-99200Y-66412D01*
X-100184Y-66003D01*
X-101348Y-63505D01*
X-101162Y-62964D01*
X-101159Y-62934D01*
G02X-100795Y-61875I2340J-213D01*
G37*
G36*
G01X-135244D02*
X-135227Y-61850D01*
X-134907Y-60919D01*
X-133479Y-60253D01*
X-130926Y-61234D01*
X-129761Y-63732D01*
X-130080Y-64748D01*
X-133649Y-66412D01*
X-134632Y-66003D01*
X-135797Y-63505D01*
X-135611Y-62964D01*
X-135608Y-62934D01*
G02X-135244Y-61875I2340J-213D01*
G37*
G36*
G01X-144102D02*
X-144086Y-61850D01*
X-143765Y-60919D01*
X-142338Y-60253D01*
X-139784Y-61234D01*
X-138619Y-63732D01*
X-138939Y-64748D01*
X-142507Y-66412D01*
X-143491Y-66003D01*
X-144655Y-63505D01*
X-144469Y-62964D01*
X-144466Y-62934D01*
G02X-144102Y-61875I2340J-213D01*
G37*
G36*
G01X-962015D02*
X-961999Y-61850D01*
X-961679Y-60919D01*
X-960251Y-60253D01*
X-957697Y-61234D01*
X-956533Y-63732D01*
X-956852Y-64748D01*
X-960420Y-66412D01*
X-961404Y-66003D01*
X-962569Y-63505D01*
X-962382Y-62964D01*
X-962380Y-62934D01*
G02X-962015Y-61875I2340J-213D01*
G37*
G36*
G01X-970874D02*
X-970857Y-61850D01*
X-970537Y-60919D01*
X-969109Y-60253D01*
X-966556Y-61234D01*
X-965391Y-63732D01*
X-965710Y-64748D01*
X-969279Y-66412D01*
X-970262Y-66003D01*
X-971427Y-63505D01*
X-971241Y-62964D01*
X-971238Y-62934D01*
G02X-970874Y-61875I2340J-213D01*
G37*
G36*
G01X-1005322D02*
X-1005306Y-61850D01*
X-1004986Y-60919D01*
X-1003558Y-60253D01*
X-1001004Y-61234D01*
X-999840Y-63732D01*
X-1000159Y-64748D01*
X-1003727Y-66412D01*
X-1004711Y-66003D01*
X-1005876Y-63505D01*
X-1005690Y-62964D01*
X-1005687Y-62934D01*
G02X-1005322Y-61875I2340J-213D01*
G37*
G36*
G01X-1014181D02*
X-1014164Y-61850D01*
X-1013844Y-60919D01*
X-1012416Y-60253D01*
X-1009863Y-61234D01*
X-1008698Y-63732D01*
X-1009017Y-64748D01*
X-1012586Y-66412D01*
X-1013569Y-66003D01*
X-1014734Y-63505D01*
X-1014548Y-62964D01*
X-1014545Y-62934D01*
G02X-1014181Y-61875I2340J-213D01*
G37*
G36*
G01X-441578Y-70154D02*
G02Y-67046I-381J1554D01*
G03X-440959Y-66560I119J486D01*
G01Y-66400D01*
X-436959D01*
Y-70800D01*
X-440959D01*
Y-70640D01*
G03X-441578Y-70154I-500J0D01*
G37*
G36*
G01X-1310178Y-70254D02*
G02Y-67146I-381J1554D01*
G03X-1309559Y-66660I119J486D01*
G01Y-66500D01*
X-1305559D01*
Y-70900D01*
X-1309559D01*
Y-70740D01*
G03X-1310178Y-70254I-500J0D01*
G37*
G36*
G01X-451706Y-67746D02*
X-451638Y-67800D01*
X-451300D01*
Y-66959D01*
X-446900D01*
Y-70959D01*
X-451300D01*
Y-70200D01*
X-451638D01*
X-451706Y-70254D01*
G02Y-67746I-994J1254D01*
G37*
G36*
G01X-85034Y-69934D02*
X-85052Y-69962D01*
X-85296Y-70727D01*
X-86708Y-71424D01*
X-89283Y-70501D01*
X-90504Y-68030D01*
X-90207Y-67007D01*
X-86678Y-65263D01*
X-85685Y-65650D01*
X-84464Y-68121D01*
X-84659Y-68730D01*
X-84660Y-68763D01*
G02X-85034Y-69934I-2348J104D01*
G37*
G36*
G01X-93892D02*
X-93910Y-69962D01*
X-94154Y-70727D01*
X-95566Y-71424D01*
X-98142Y-70501D01*
X-99362Y-68030D01*
X-99066Y-67007D01*
X-95536Y-65263D01*
X-94543Y-65650D01*
X-93323Y-68121D01*
X-93517Y-68730D01*
X-93518Y-68763D01*
G02X-93892Y-69934I-2348J104D01*
G37*
G36*
G01X-128341Y-69934D02*
X-128359Y-69962D01*
X-128603Y-70727D01*
X-130015Y-71424D01*
X-132590Y-70501D01*
X-133811Y-68030D01*
X-133515Y-67007D01*
X-129985Y-65263D01*
X-128992Y-65650D01*
X-127771Y-68121D01*
X-127966Y-68730D01*
X-127967Y-68763D01*
G02X-128341Y-69934I-2348J104D01*
G37*
G36*
G01X-137199D02*
X-137217Y-69962D01*
X-137461Y-70727D01*
X-138874Y-71424D01*
X-141449Y-70501D01*
X-142669Y-68030D01*
X-142373Y-67007D01*
X-138843Y-65263D01*
X-137850Y-65650D01*
X-136630Y-68121D01*
X-136824Y-68730D01*
X-136826Y-68763D01*
G02X-137199Y-69934I-2348J104D01*
G37*
G36*
G01X-955113Y-69934D02*
X-955131Y-69962D01*
X-955375Y-70727D01*
X-956787Y-71424D01*
X-959362Y-70501D01*
X-960583Y-68030D01*
X-960286Y-67007D01*
X-956756Y-65263D01*
X-955764Y-65650D01*
X-954543Y-68121D01*
X-954737Y-68730D01*
X-954739Y-68763D01*
G02X-955113Y-69934I-2348J104D01*
G37*
G36*
G01X-963971D02*
X-963989Y-69962D01*
X-964233Y-70727D01*
X-965645Y-71424D01*
X-968220Y-70501D01*
X-969441Y-68030D01*
X-969144Y-67007D01*
X-965615Y-65263D01*
X-964622Y-65650D01*
X-963401Y-68121D01*
X-963596Y-68730D01*
X-963597Y-68763D01*
G02X-963971Y-69934I-2348J104D01*
G37*
G36*
G01X-998420Y-69934D02*
X-998438Y-69962D01*
X-998682Y-70727D01*
X-1000094Y-71424D01*
X-1002669Y-70501D01*
X-1003890Y-68030D01*
X-1003593Y-67007D01*
X-1000064Y-65263D01*
X-999071Y-65650D01*
X-997850Y-68121D01*
X-998045Y-68730D01*
X-998046Y-68763D01*
G02X-998420Y-69934I-2348J104D01*
G37*
G36*
G01X-1007278D02*
X-1007296Y-69962D01*
X-1007540Y-70727D01*
X-1008952Y-71424D01*
X-1011527Y-70501D01*
X-1012748Y-68030D01*
X-1012452Y-67007D01*
X-1008922Y-65263D01*
X-1007929Y-65650D01*
X-1006708Y-68121D01*
X-1006903Y-68730D01*
X-1006904Y-68763D01*
G02X-1007278Y-69934I-2348J104D01*
G37*
G36*
G01X-1319450Y-72700D02*
Y-71059D01*
X-1319900D01*
Y-67059D01*
X-1315500D01*
Y-71059D01*
X-1315950D01*
Y-72700D01*
G02X-1319450I-1750J0D01*
G37*
G36*
G01X-441959Y-72350D02*
X-440959D01*
Y-71900D01*
X-436959D01*
Y-76300D01*
X-440959D01*
Y-75850D01*
X-441959D01*
G02Y-72350I0J1750D01*
G37*
G36*
G01X-1310559Y-72450D02*
X-1309559D01*
Y-72000D01*
X-1305559D01*
Y-76400D01*
X-1309559D01*
Y-75950D01*
X-1310559D01*
G02Y-72450I0J1750D01*
G37*
G36*
G01X-91936Y-76836D02*
X-91920Y-76810D01*
X-91600Y-75879D01*
X-90172Y-75214D01*
X-87619Y-76194D01*
X-86454Y-78692D01*
X-86773Y-79708D01*
X-90342Y-81372D01*
X-91325Y-80964D01*
X-92490Y-78466D01*
X-92304Y-77924D01*
X-92301Y-77894D01*
G02X-91936Y-76836I2340J-213D01*
G37*
G36*
G01X-100795D02*
X-100778Y-76810D01*
X-100458Y-75879D01*
X-99031Y-75214D01*
X-96477Y-76194D01*
X-95312Y-78692D01*
X-95632Y-79708D01*
X-99200Y-81372D01*
X-100184Y-80964D01*
X-101348Y-78466D01*
X-101162Y-77924D01*
X-101159Y-77894D01*
G02X-100795Y-76836I2340J-213D01*
G37*
G36*
G01X-135244D02*
X-135227Y-76810D01*
X-134907Y-75879D01*
X-133479Y-75214D01*
X-130926Y-76194D01*
X-129761Y-78692D01*
X-130080Y-79708D01*
X-133649Y-81372D01*
X-134632Y-80964D01*
X-135797Y-78466D01*
X-135611Y-77924D01*
X-135608Y-77894D01*
G02X-135244Y-76836I2340J-213D01*
G37*
G36*
G01X-144102D02*
X-144086Y-76810D01*
X-143765Y-75879D01*
X-142338Y-75214D01*
X-139784Y-76194D01*
X-138619Y-78692D01*
X-138939Y-79708D01*
X-142507Y-81372D01*
X-143491Y-80964D01*
X-144655Y-78466D01*
X-144469Y-77924D01*
X-144466Y-77894D01*
G02X-144102Y-76836I2340J-213D01*
G37*
G36*
G01X-962015D02*
X-961999Y-76810D01*
X-961679Y-75879D01*
X-960251Y-75214D01*
X-957697Y-76194D01*
X-956533Y-78692D01*
X-956852Y-79708D01*
X-960420Y-81372D01*
X-961404Y-80964D01*
X-962569Y-78466D01*
X-962382Y-77924D01*
X-962380Y-77894D01*
G02X-962015Y-76836I2340J-213D01*
G37*
G36*
G01X-970874D02*
X-970857Y-76810D01*
X-970537Y-75879D01*
X-969109Y-75214D01*
X-966556Y-76194D01*
X-965391Y-78692D01*
X-965710Y-79708D01*
X-969279Y-81372D01*
X-970262Y-80964D01*
X-971427Y-78466D01*
X-971241Y-77924D01*
X-971238Y-77894D01*
G02X-970874Y-76836I2340J-213D01*
G37*
G36*
G01X-1005322D02*
X-1005306Y-76810D01*
X-1004986Y-75879D01*
X-1003558Y-75214D01*
X-1001004Y-76194D01*
X-999840Y-78692D01*
X-1000159Y-79708D01*
X-1003727Y-81372D01*
X-1004711Y-80964D01*
X-1005876Y-78466D01*
X-1005690Y-77924D01*
X-1005687Y-77894D01*
G02X-1005322Y-76836I2340J-213D01*
G37*
G36*
G01X-1014181D02*
X-1014164Y-76810D01*
X-1013844Y-75879D01*
X-1012416Y-75214D01*
X-1009863Y-76194D01*
X-1008698Y-78692D01*
X-1009017Y-79708D01*
X-1012586Y-81372D01*
X-1013569Y-80964D01*
X-1014734Y-78466D01*
X-1014548Y-77924D01*
X-1014545Y-77894D01*
G02X-1014181Y-76836I2340J-213D01*
G37*
G36*
G01X-430958Y-78400D02*
G02Y-80800I1058J-1200D01*
G01X-431841D01*
Y-81800D01*
X-435841D01*
Y-77400D01*
X-435041D01*
Y-76300D01*
X-435841D01*
Y-71900D01*
X-435041D01*
Y-70800D01*
X-435841D01*
Y-66400D01*
X-431841D01*
Y-70800D01*
X-432641D01*
Y-71900D01*
X-431841D01*
Y-76300D01*
X-432641D01*
Y-77400D01*
X-431841D01*
Y-78400D01*
X-430958D01*
G37*
G36*
G01X-1303641Y-83090D02*
Y-81900D01*
X-1304441D01*
Y-77500D01*
X-1303641D01*
Y-76400D01*
X-1304441D01*
Y-72000D01*
X-1303641D01*
Y-70900D01*
X-1304441D01*
Y-66500D01*
X-1300441D01*
Y-70900D01*
X-1301241D01*
Y-72000D01*
X-1300441D01*
Y-76400D01*
X-1301241D01*
Y-77500D01*
X-1300441D01*
Y-81900D01*
X-1301241D01*
Y-82997D01*
G02X-1303641Y-83090I-1159J-1103D01*
G37*
G36*
G01X-85034Y-84895D02*
X-85052Y-84923D01*
X-85296Y-85687D01*
X-86708Y-86385D01*
X-89283Y-85462D01*
X-90504Y-82991D01*
X-90207Y-81968D01*
X-86678Y-80224D01*
X-85685Y-80610D01*
X-84464Y-83081D01*
X-84659Y-83691D01*
X-84660Y-83724D01*
G02X-85034Y-84895I-2348J104D01*
G37*
G36*
G01X-93892D02*
X-93910Y-84923D01*
X-94154Y-85687D01*
X-95566Y-86385D01*
X-98142Y-85462D01*
X-99362Y-82991D01*
X-99066Y-81968D01*
X-95536Y-80224D01*
X-94543Y-80610D01*
X-93323Y-83081D01*
X-93517Y-83691D01*
X-93518Y-83724D01*
G02X-93892Y-84895I-2348J104D01*
G37*
G36*
G01X-128341Y-84895D02*
X-128359Y-84923D01*
X-128603Y-85687D01*
X-130015Y-86385D01*
X-132590Y-85462D01*
X-133811Y-82991D01*
X-133515Y-81968D01*
X-129985Y-80224D01*
X-128992Y-80610D01*
X-127771Y-83081D01*
X-127966Y-83690D01*
X-127967Y-83724D01*
G02X-128341Y-84895I-2348J104D01*
G37*
G36*
G01X-137199D02*
X-137217Y-84923D01*
X-137461Y-85687D01*
X-138874Y-86385D01*
X-141449Y-85462D01*
X-142669Y-82991D01*
X-142373Y-81968D01*
X-138843Y-80224D01*
X-137850Y-80610D01*
X-136630Y-83081D01*
X-136824Y-83690D01*
X-136826Y-83724D01*
G02X-137199Y-84895I-2348J104D01*
G37*
G36*
G01X-955113Y-84895D02*
X-955131Y-84923D01*
X-955375Y-85687D01*
X-956787Y-86385D01*
X-959362Y-85462D01*
X-960583Y-82991D01*
X-960286Y-81968D01*
X-956756Y-80224D01*
X-955764Y-80610D01*
X-954543Y-83081D01*
X-954737Y-83691D01*
X-954739Y-83724D01*
G02X-955113Y-84895I-2348J104D01*
G37*
G36*
G01X-963971D02*
X-963989Y-84923D01*
X-964233Y-85687D01*
X-965645Y-86385D01*
X-968220Y-85462D01*
X-969441Y-82991D01*
X-969144Y-81968D01*
X-965615Y-80224D01*
X-964622Y-80610D01*
X-963401Y-83081D01*
X-963596Y-83691D01*
X-963597Y-83724D01*
G02X-963971Y-84895I-2348J104D01*
G37*
G36*
G01X-998420Y-84895D02*
X-998438Y-84923D01*
X-998682Y-85687D01*
X-1000094Y-86385D01*
X-1002669Y-85462D01*
X-1003890Y-82991D01*
X-1003593Y-81968D01*
X-1000064Y-80224D01*
X-999071Y-80610D01*
X-997850Y-83081D01*
X-998045Y-83690D01*
X-998046Y-83724D01*
G02X-998420Y-84895I-2348J104D01*
G37*
G36*
G01X-1007278D02*
X-1007296Y-84923D01*
X-1007540Y-85687D01*
X-1008952Y-86385D01*
X-1011527Y-85462D01*
X-1012748Y-82991D01*
X-1012452Y-81968D01*
X-1008922Y-80224D01*
X-1007929Y-80610D01*
X-1006708Y-83081D01*
X-1006903Y-83690D01*
X-1006904Y-83724D01*
G02X-1007278Y-84895I-2348J104D01*
G37*
G36*
G01X-455228Y-88300D02*
Y-83800D01*
X-452028D01*
Y-88300D01*
G02X-455228I-1600J0D01*
G37*
G36*
G01X-449728Y-88800D02*
Y-87800D01*
X-450328D01*
Y-83800D01*
X-445928D01*
Y-87800D01*
X-446528D01*
Y-88800D01*
G02X-449728I-1600J0D01*
G37*
G36*
G01X-437057Y-90826D02*
X-436980Y-90812D01*
X-433668Y-87500D01*
X-433692Y-87371D01*
G02X-430864Y-88075I1574J289D01*
G01X-430918Y-88143D01*
Y-88144D01*
X-430983Y-88209D01*
G02X-430991Y-88217I-1136J1127D01*
G01X-435168Y-92394D01*
X-435174Y-92490D01*
G02X-437057Y-90826I-1598J90D01*
G37*
G36*
G01X-91936Y-91796D02*
X-91920Y-91771D01*
X-91600Y-90840D01*
X-90172Y-90174D01*
X-87619Y-91155D01*
X-86454Y-93653D01*
X-86773Y-94669D01*
X-90342Y-96333D01*
X-91325Y-95924D01*
X-92490Y-93427D01*
X-92304Y-92885D01*
X-92301Y-92855D01*
G02X-91936Y-91796I2340J-213D01*
G37*
G36*
G01X-100795D02*
X-100778Y-91771D01*
X-100458Y-90840D01*
X-99031Y-90174D01*
X-96477Y-91155D01*
X-95312Y-93653D01*
X-95632Y-94669D01*
X-99200Y-96333D01*
X-100184Y-95924D01*
X-101348Y-93427D01*
X-101162Y-92885D01*
X-101159Y-92855D01*
G02X-100795Y-91796I2340J-213D01*
G37*
G36*
G01X-135244D02*
X-135227Y-91771D01*
X-134907Y-90840D01*
X-133479Y-90174D01*
X-130926Y-91155D01*
X-129761Y-93653D01*
X-130080Y-94669D01*
X-133649Y-96333D01*
X-134632Y-95924D01*
X-135797Y-93427D01*
X-135611Y-92885D01*
X-135608Y-92855D01*
G02X-135244Y-91796I2340J-213D01*
G37*
G36*
G01X-144102D02*
X-144086Y-91771D01*
X-143765Y-90840D01*
X-142338Y-90174D01*
X-139784Y-91155D01*
X-138619Y-93653D01*
X-138939Y-94669D01*
X-142507Y-96333D01*
X-143491Y-95924D01*
X-144655Y-93427D01*
X-144469Y-92885D01*
X-144466Y-92855D01*
G02X-144102Y-91796I2340J-213D01*
G37*
G36*
G01X-962015D02*
X-961999Y-91771D01*
X-961679Y-90840D01*
X-960251Y-90174D01*
X-957697Y-91155D01*
X-956533Y-93653D01*
X-956852Y-94669D01*
X-960420Y-96333D01*
X-961404Y-95924D01*
X-962569Y-93427D01*
X-962382Y-92885D01*
X-962380Y-92855D01*
G02X-962015Y-91796I2340J-213D01*
G37*
G36*
G01X-970874D02*
X-970857Y-91771D01*
X-970537Y-90840D01*
X-969109Y-90174D01*
X-966556Y-91155D01*
X-965391Y-93653D01*
X-965710Y-94669D01*
X-969279Y-96333D01*
X-970262Y-95924D01*
X-971427Y-93427D01*
X-971241Y-92885D01*
X-971238Y-92855D01*
G02X-970874Y-91796I2340J-213D01*
G37*
G36*
G01X-1005322D02*
X-1005306Y-91771D01*
X-1004986Y-90840D01*
X-1003558Y-90174D01*
X-1001004Y-91155D01*
X-999840Y-93653D01*
X-1000159Y-94669D01*
X-1003727Y-96333D01*
X-1004711Y-95924D01*
X-1005876Y-93427D01*
X-1005690Y-92885D01*
X-1005687Y-92855D01*
G02X-1005322Y-91796I2340J-213D01*
G37*
G36*
G01X-1014181D02*
X-1014164Y-91771D01*
X-1013844Y-90840D01*
X-1012416Y-90174D01*
X-1009863Y-91155D01*
X-1008698Y-93653D01*
X-1009017Y-94669D01*
X-1012586Y-96333D01*
X-1013569Y-95924D01*
X-1014734Y-93427D01*
X-1014548Y-92885D01*
X-1014545Y-92855D01*
G02X-1014181Y-91796I2340J-213D01*
G37*
G36*
G01X-85034Y-99855D02*
X-85052Y-99883D01*
X-85296Y-100648D01*
X-86708Y-101346D01*
X-89283Y-100423D01*
X-90504Y-97952D01*
X-90207Y-96928D01*
X-86678Y-95185D01*
X-85685Y-95571D01*
X-84464Y-98042D01*
X-84659Y-98651D01*
X-84660Y-98684D01*
G02X-85034Y-99855I-2348J104D01*
G37*
G36*
G01X-93892D02*
X-93910Y-99883D01*
X-94154Y-100648D01*
X-95566Y-101346D01*
X-98142Y-100423D01*
X-99362Y-97952D01*
X-99066Y-96928D01*
X-95536Y-95185D01*
X-94543Y-95571D01*
X-93323Y-98042D01*
X-93517Y-98651D01*
X-93518Y-98684D01*
G02X-93892Y-99855I-2348J104D01*
G37*
G36*
G01X-128341Y-99855D02*
X-128359Y-99883D01*
X-128603Y-100648D01*
X-130015Y-101346D01*
X-132590Y-100423D01*
X-133811Y-97952D01*
X-133515Y-96928D01*
X-129985Y-95185D01*
X-128992Y-95571D01*
X-127771Y-98042D01*
X-127966Y-98651D01*
X-127967Y-98684D01*
G02X-128341Y-99855I-2348J104D01*
G37*
G36*
G01X-137199D02*
X-137217Y-99883D01*
X-137461Y-100648D01*
X-138874Y-101346D01*
X-141449Y-100423D01*
X-142669Y-97952D01*
X-142373Y-96928D01*
X-138843Y-95185D01*
X-137850Y-95571D01*
X-136630Y-98042D01*
X-136824Y-98651D01*
X-136826Y-98684D01*
G02X-137199Y-99855I-2348J104D01*
G37*
G36*
G01X-955113Y-99855D02*
X-955131Y-99883D01*
X-955375Y-100648D01*
X-956787Y-101346D01*
X-959362Y-100423D01*
X-960583Y-97952D01*
X-960286Y-96928D01*
X-956756Y-95185D01*
X-955764Y-95571D01*
X-954543Y-98042D01*
X-954737Y-98651D01*
X-954739Y-98684D01*
G02X-955113Y-99855I-2348J104D01*
G37*
G36*
G01X-963971D02*
X-963989Y-99883D01*
X-964233Y-100648D01*
X-965645Y-101346D01*
X-968220Y-100423D01*
X-969441Y-97952D01*
X-969144Y-96928D01*
X-965615Y-95185D01*
X-964622Y-95571D01*
X-963401Y-98042D01*
X-963596Y-98651D01*
X-963597Y-98684D01*
G02X-963971Y-99855I-2348J104D01*
G37*
G36*
G01X-998420Y-99855D02*
X-998438Y-99883D01*
X-998682Y-100648D01*
X-1000094Y-101346D01*
X-1002669Y-100423D01*
X-1003890Y-97952D01*
X-1003593Y-96928D01*
X-1000064Y-95185D01*
X-999071Y-95571D01*
X-997850Y-98042D01*
X-998045Y-98651D01*
X-998046Y-98684D01*
G02X-998420Y-99855I-2348J104D01*
G37*
G36*
G01X-1007278D02*
X-1007296Y-99883D01*
X-1007540Y-100648D01*
X-1008952Y-101346D01*
X-1011527Y-100423D01*
X-1012748Y-97952D01*
X-1012452Y-96928D01*
X-1008922Y-95185D01*
X-1007929Y-95571D01*
X-1006708Y-98042D01*
X-1006903Y-98651D01*
X-1006904Y-98684D01*
G02X-1007278Y-99855I-2348J104D01*
G37*
G36*
G01X-293150Y-80703D02*
Y-92362D01*
G02X-316772I-11811J0D01*
G01Y-80703D01*
G02X-293150I11811J11963D01*
G37*
G36*
G01X-1167165D02*
Y-92362D01*
G02X-1190787I-11811J0D01*
G01Y-80703D01*
G02X-1167165I11811J11963D01*
G37*
G36*
G01X-549055Y-104325D02*
Y-115984D01*
G02X-572677I-11811J0D01*
G01Y-104325D01*
G02X-549055I11811J11963D01*
G37*
G36*
G01X-515763Y-129075D02*
X-515814Y-129050D01*
X-520800D01*
Y-128011D01*
X-520819Y-127965D01*
G02Y-126635I1619J665D01*
G01X-520800Y-126589D01*
Y-125550D01*
X-514475D01*
X-513763Y-126263D01*
G02X-515763Y-129075I-1237J-1237D01*
G37*
G36*
G01X-541237Y-126263D02*
X-540575Y-125600D01*
X-537846D01*
X-537596Y-125350D01*
X-533300D01*
Y-129350D01*
X-537700D01*
X-537950Y-129100D01*
X-539289D01*
X-539335Y-129119D01*
G02X-541237Y-126263I-665J1619D01*
G37*
G36*
G01X-20905Y-117711D02*
Y-129370D01*
G02X-44528I-11811J0D01*
G01Y-117711D01*
G02X-20905I11811J11963D01*
G37*
G36*
G01X-1194760Y-141597D02*
Y-143638D01*
X-1199260D01*
Y-141590D01*
G02Y-139197I2252J1197D01*
G01Y-136079D01*
G02Y-133685I2252J1197D01*
G01Y-131638D01*
X-1194760D01*
Y-133679D01*
G02Y-136085I-2248J-1203D01*
G01Y-139190D01*
G02Y-141597I-2248J-1203D01*
G37*
G36*
G01X-980742Y-141594D02*
Y-143638D01*
X-985242D01*
Y-141594D01*
G02Y-139194I2250J1200D01*
G01Y-136082D01*
G02Y-133682I2250J1200D01*
G01Y-131638D01*
X-980742D01*
Y-133682D01*
G02Y-136082I-2250J-1200D01*
G01Y-139194D01*
G02Y-141594I-2250J-1200D01*
G37*
G36*
G01X-1012238D02*
Y-143638D01*
X-1016738D01*
Y-141594D01*
G02Y-139194I2250J1200D01*
G01Y-136082D01*
G02Y-133682I2250J1200D01*
G01Y-131638D01*
X-1012238D01*
Y-133682D01*
G02Y-136082I-2250J-1200D01*
G01Y-139194D01*
G02Y-141594I-2250J-1200D01*
G37*
G36*
G01X-972868Y-146712D02*
Y-148756D01*
X-977368D01*
Y-146712D01*
G02Y-144312I2250J1200D01*
G01Y-141200D01*
G02Y-138800I2250J1200D01*
G01Y-136756D01*
X-972868D01*
Y-138800D01*
G02Y-141200I-2250J-1200D01*
G01Y-144312D01*
G02Y-146712I-2250J-1200D01*
G37*
G36*
G01X-285311Y-146715D02*
Y-148756D01*
X-289811D01*
Y-146709D01*
G02Y-144315I2252J1197D01*
G01Y-141197D01*
G02Y-138803I2252J1197D01*
G01Y-136756D01*
X-285311D01*
Y-138797D01*
G02Y-141203I-2248J-1203D01*
G01Y-144309D01*
G02Y-146715I-2248J-1203D01*
G37*
G36*
G01X-1155390D02*
Y-148756D01*
X-1159890D01*
Y-146709D01*
G02Y-144315I2252J1197D01*
G01Y-141197D01*
G02Y-138803I2252J1197D01*
G01Y-136756D01*
X-1155390D01*
Y-138797D01*
G02Y-141203I-2248J-1203D01*
G01Y-144309D01*
G02Y-146715I-2248J-1203D01*
G37*
G36*
G01X-1136380Y-124446D02*
Y-98180D01*
X-1089610D01*
Y-159600D01*
X-1136380D01*
Y-127995D01*
G02Y-124446I4293J1775D01*
G37*
G36*
G01X-266120Y-124059D02*
Y-98150D01*
X-219800D01*
Y-124767D01*
X-219788Y-124804D01*
G02Y-127637I-4425J-1416D01*
G01X-219800Y-127674D01*
Y-159890D01*
X-266120D01*
Y-128382D01*
G02Y-124059I4112J2162D01*
G37*
G36*
G01X-324681Y-158132D02*
Y-160173D01*
X-329181D01*
Y-158126D01*
G02Y-155732I2252J1197D01*
G01Y-152614D01*
G02Y-150221I2252J1197D01*
G01Y-148173D01*
X-324681D01*
Y-150214D01*
G02Y-152621I-2248J-1203D01*
G01Y-155726D01*
G02Y-158132I-2248J-1203D01*
G37*
G36*
G01X-1194760D02*
Y-160173D01*
X-1199260D01*
Y-158126D01*
G02Y-155732I2252J1197D01*
G01Y-152614D01*
G02Y-150221I2252J1197D01*
G01Y-148173D01*
X-1194760D01*
Y-150214D01*
G02Y-152621I-2248J-1203D01*
G01Y-155726D01*
G02Y-158132I-2248J-1203D01*
G37*
G36*
G01X-980742Y-158129D02*
Y-160173D01*
X-985242D01*
Y-158129D01*
G02Y-155729I2250J1200D01*
G01Y-152617D01*
G02Y-150217I2250J1200D01*
G01Y-148173D01*
X-980742D01*
Y-150217D01*
G02Y-152617I-2250J-1200D01*
G01Y-155729D01*
G02Y-158129I-2250J-1200D01*
G37*
G36*
G01X-1012238D02*
Y-160173D01*
X-1016738D01*
Y-158129D01*
G02Y-155729I2250J1200D01*
G01Y-152617D01*
G02Y-150217I2250J1200D01*
G01Y-148173D01*
X-1012238D01*
Y-150217D01*
G02Y-152617I-2250J-1200D01*
G01Y-155729D01*
G02Y-158129I-2250J-1200D01*
G37*
G36*
G01X-972868Y-163247D02*
Y-165291D01*
X-977368D01*
Y-163247D01*
G02Y-160847I2250J1200D01*
G01Y-157735D01*
G02Y-155335I2250J1200D01*
G01Y-153291D01*
X-972868D01*
Y-155335D01*
G02Y-157735I-2250J-1200D01*
G01Y-160847D01*
G02Y-163247I-2250J-1200D01*
G37*
G36*
G01X-285311Y-163250D02*
Y-165291D01*
X-289811D01*
Y-163244D01*
G02Y-160850I2252J1197D01*
G01Y-157732D01*
G02Y-155339I2252J1197D01*
G01Y-153291D01*
X-285311D01*
Y-155332D01*
G02Y-157739I-2248J-1203D01*
G01Y-160844D01*
G02Y-163250I-2248J-1203D01*
G37*
G36*
G01X-1155390D02*
Y-165291D01*
X-1159890D01*
Y-163244D01*
G02Y-160850I2252J1197D01*
G01Y-157732D01*
G02Y-155339I2252J1197D01*
G01Y-153291D01*
X-1155390D01*
Y-155332D01*
G02Y-157739I-2248J-1203D01*
G01Y-160844D01*
G02Y-163250I-2248J-1203D01*
G37*
G36*
G01X-980742Y-174665D02*
Y-176709D01*
X-985242D01*
Y-174665D01*
G02Y-172265I2250J1200D01*
G01Y-169153D01*
G02Y-166753I2250J1200D01*
G01Y-164709D01*
X-980742D01*
Y-166753D01*
G02Y-169153I-2250J-1200D01*
G01Y-172265D01*
G02Y-174665I-2250J-1200D01*
G37*
G36*
G01X-1012238D02*
Y-176709D01*
X-1016738D01*
Y-174665D01*
G02Y-172265I2250J1200D01*
G01Y-169153D01*
G02Y-166753I2250J1200D01*
G01Y-164709D01*
X-1012238D01*
Y-166753D01*
G02Y-169153I-2250J-1200D01*
G01Y-172265D01*
G02Y-174665I-2250J-1200D01*
G37*
G36*
G01X-293185Y-174668D02*
Y-176709D01*
X-297685D01*
Y-174661D01*
G02Y-172268I2252J1197D01*
G01Y-169150D01*
G02Y-166756I2252J1197D01*
G01Y-164709D01*
X-293185D01*
Y-166750D01*
G02Y-169156I-2248J-1203D01*
G01Y-172261D01*
G02Y-174668I-2248J-1203D01*
G37*
G36*
G01X-308933D02*
Y-176709D01*
X-313433D01*
Y-174661D01*
G02Y-172268I2252J1197D01*
G01Y-169150D01*
G02Y-166756I2252J1197D01*
G01Y-164709D01*
X-308933D01*
Y-166750D01*
G02Y-169156I-2248J-1203D01*
G01Y-172261D01*
G02Y-174668I-2248J-1203D01*
G37*
G36*
G01X-324681D02*
Y-176709D01*
X-329181D01*
Y-174661D01*
G02Y-172268I2252J1197D01*
G01Y-169150D01*
G02Y-166756I2252J1197D01*
G01Y-164709D01*
X-324681D01*
Y-166750D01*
G02Y-169156I-2248J-1203D01*
G01Y-172261D01*
G02Y-174668I-2248J-1203D01*
G37*
G36*
G01X-1163264D02*
Y-176709D01*
X-1167764D01*
Y-174661D01*
G02Y-172268I2252J1197D01*
G01Y-169150D01*
G02Y-166756I2252J1197D01*
G01Y-164709D01*
X-1163264D01*
Y-166750D01*
G02Y-169156I-2248J-1203D01*
G01Y-172261D01*
G02Y-174668I-2248J-1203D01*
G37*
G36*
G01X-1179012D02*
Y-176709D01*
X-1183512D01*
Y-174661D01*
G02Y-172268I2252J1197D01*
G01Y-169150D01*
G02Y-166756I2252J1197D01*
G01Y-164709D01*
X-1179012D01*
Y-166750D01*
G02Y-169156I-2248J-1203D01*
G01Y-172261D01*
G02Y-174668I-2248J-1203D01*
G37*
G36*
G01X-1194760D02*
Y-176709D01*
X-1199260D01*
Y-174661D01*
G02Y-172268I2252J1197D01*
G01Y-169150D01*
G02Y-166756I2252J1197D01*
G01Y-164709D01*
X-1194760D01*
Y-166750D01*
G02Y-169156I-2248J-1203D01*
G01Y-172261D01*
G02Y-174668I-2248J-1203D01*
G37*
G36*
G01X-1004364Y-179783D02*
Y-181827D01*
X-1008864D01*
Y-179783D01*
G02Y-177383I2250J1200D01*
G01Y-174271D01*
G02Y-171871I2250J1200D01*
G01Y-169827D01*
X-1004364D01*
Y-171871D01*
G02Y-174271I-2250J-1200D01*
G01Y-177383D01*
G02Y-179783I-2250J-1200D01*
G37*
G36*
G01X-285311Y-179889D02*
Y-181827D01*
X-289811D01*
Y-179883D01*
G02Y-177283I2252J1300D01*
G01Y-174268D01*
G02Y-171874I2252J1197D01*
G01Y-169827D01*
X-285311D01*
Y-171868D01*
G02Y-174274I-2248J-1203D01*
G01Y-177277D01*
G02Y-179889I-2248J-1306D01*
G37*
G36*
G01X-301059D02*
Y-181827D01*
X-305559D01*
Y-179883D01*
G02Y-177283I2252J1300D01*
G01Y-174268D01*
G02Y-171874I2252J1197D01*
G01Y-169827D01*
X-301059D01*
Y-171868D01*
G02Y-174274I-2248J-1203D01*
G01Y-177277D01*
G02Y-179889I-2248J-1306D01*
G37*
G36*
G01X-316807D02*
Y-181827D01*
X-321307D01*
Y-179883D01*
G02Y-177283I2252J1300D01*
G01Y-174268D01*
G02Y-171874I2252J1197D01*
G01Y-169827D01*
X-316807D01*
Y-171868D01*
G02Y-174274I-2248J-1203D01*
G01Y-177277D01*
G02Y-179889I-2248J-1306D01*
G37*
G36*
G01X-1155390Y-179786D02*
Y-181827D01*
X-1159890D01*
Y-179779D01*
G02Y-177386I2252J1197D01*
G01Y-174268D01*
G02Y-171874I2252J1197D01*
G01Y-169827D01*
X-1155390D01*
Y-171868D01*
G02Y-174274I-2248J-1203D01*
G01Y-177379D01*
G02Y-179786I-2248J-1203D01*
G37*
G36*
G01X-1171138D02*
Y-181827D01*
X-1175638D01*
Y-179779D01*
G02Y-177386I2252J1197D01*
G01Y-174268D01*
G02Y-171874I2252J1197D01*
G01Y-169827D01*
X-1171138D01*
Y-171868D01*
G02Y-174274I-2248J-1203D01*
G01Y-177379D01*
G02Y-179786I-2248J-1203D01*
G37*
G36*
G01X-1186886D02*
Y-181827D01*
X-1191386D01*
Y-179779D01*
G02Y-177386I2252J1197D01*
G01Y-174268D01*
G02Y-171874I2252J1197D01*
G01Y-169827D01*
X-1186886D01*
Y-171868D01*
G02Y-174274I-2248J-1203D01*
G01Y-177379D01*
G02Y-179786I-2248J-1203D01*
G37*
G36*
G01X-276690Y-178957D02*
G02Y-177443I-1410J757D01*
G03X-275810I440J237D01*
G02Y-178957I1410J-757D01*
G03X-276690I-440J-237D01*
G37*
G36*
G01X-1188041Y-159743D02*
G02X-1190226I-1093J-2304D01*
G03Y-158840I-214J452D01*
G02X-1188041I1093J2304D01*
G03Y-159743I214J-452D01*
G37*
G36*
G01X-1172293D02*
G02X-1174478I-1093J-2304D01*
G03Y-158840I-214J452D01*
G02Y-154231I1093J2304D01*
G03Y-153328I-214J452D01*
G02Y-148720I1093J2304D01*
G03Y-147816I-214J452D01*
G02Y-143208I1093J2304D01*
G03Y-142304I-214J452D01*
G02X-1175862Y-139391I1093J2304D01*
G01X-1175828Y-139254D01*
X-1177143Y-137940D01*
X-1178825Y-139622D01*
X-1178790Y-139760D01*
G02X-1180167Y-142698I-2470J-633D01*
G03Y-143601I214J-452D01*
G02Y-148210I-1093J-2304D01*
G03Y-149113I214J-452D01*
G02Y-153721I-1093J-2304D01*
G03Y-154625I214J-452D01*
G02X-1182352I-1093J-2304D01*
G03Y-153721I-214J452D01*
G02Y-149113I1093J2304D01*
G03Y-148210I-214J452D01*
G02X-1183742Y-145322I1093J2304D01*
G01X-1183710Y-145187D01*
X-1186100Y-142797D01*
Y-141698D01*
G03X-1187015Y-141419I-500J0D01*
G02X-1188041Y-142304I-2118J1419D01*
G03Y-143208I214J-452D01*
G02X-1190226I-1093J-2304D01*
G03Y-142304I-214J452D01*
G02Y-137696I1093J2304D01*
G03Y-136792I-214J452D01*
G02X-1187015Y-133069I1093J2304D01*
G03X-1186100Y-132790I415J278D01*
G01Y-123103D01*
X-1177699Y-114702D01*
X-1177689Y-114616D01*
G02X-1175916Y-116389I1589J-184D01*
G01X-1176002Y-116399D01*
X-1183700Y-124097D01*
Y-132528D01*
G03X-1182882Y-132914I500J0D01*
G02X-1179872Y-132743I1622J-1968D01*
G03X-1179100Y-132323I272J419D01*
G01Y-128203D01*
X-1171500Y-120603D01*
Y-115658D01*
G02X-1169100I1200J1058D01*
G01Y-120096D01*
G03X-1168246Y-120449I500J0D01*
G01X-1161697Y-113900D01*
X-1161058D01*
G02X-1158762Y-114087I1058J-1200D01*
G03X-1158021Y-114124I387J317D01*
G01X-1155600Y-111703D01*
Y-108958D01*
G02X-1153200I1200J1058D01*
G01Y-112697D01*
X-1167900Y-127397D01*
Y-132487D01*
G03X-1167090Y-132879I500J0D01*
G02X-1164419Y-137186I1579J-2003D01*
G03Y-138090I214J-452D01*
G02X-1167952Y-139655I-1093J-2304D01*
G01X-1167909Y-139512D01*
X-1170300Y-137121D01*
Y-127104D01*
G03X-1171154Y-126751I-500J0D01*
G01X-1174600Y-130197D01*
Y-131523D01*
G03X-1173983Y-132009I500J0D01*
G02X-1172293Y-136792I597J-2479D01*
G03Y-137696I214J-452D01*
G02Y-142304I-1093J-2304D01*
G03Y-143208I214J-452D01*
G02Y-147816I-1093J-2304D01*
G03Y-148720I214J-452D01*
G02Y-153328I-1093J-2304D01*
G03Y-154231I214J-452D01*
G02Y-158840I-1093J-2304D01*
G03Y-159743I214J-452D01*
G37*
G36*
G01X-317963D02*
G02X-320148I-1093J-2304D01*
G03Y-158840I-214J452D01*
G02X-317963I1093J2304D01*
G03Y-159743I214J-452D01*
G37*
G36*
G01X-1164419Y-154625D02*
G02X-1166604I-1093J-2304D01*
G03Y-153721I-214J452D01*
G02X-1164419I1093J2304D01*
G03Y-154625I214J-452D01*
G37*
G36*
G01X-294341D02*
G02X-296526I-1093J-2304D01*
G03Y-153721I-214J452D01*
G02X-294341I1093J2304D01*
G03Y-154625I214J-452D01*
G37*
G36*
G01X-792440Y-150508D02*
G02X-795017I-1289J-3468D01*
G03Y-149571I-174J469D01*
G02Y-142634I1289J3468D01*
G03Y-141697I-174J469D01*
G02X-792440I1289J3468D01*
G03Y-142634I174J-469D01*
G02Y-149571I-1289J-3468D01*
G03Y-150508I174J-469D01*
G37*
G36*
G01X-436518Y-147362D02*
G02X-438410Y-144838I-5412J-2087D01*
G03X-437619Y-144333I303J397D01*
G02X-435811Y-146743I3564J789D01*
G03X-436518Y-147362I-240J-438D01*
G37*
G36*
G01X-294341Y-138090D02*
G02X-296526I-1093J-2304D01*
G03Y-137186I-214J452D01*
G02X-294341I1093J2304D01*
G03Y-138090I214J-452D01*
G37*
G36*
G01X-896380Y-131357D02*
G02X-898620I-1120J-1143D01*
G03X-898970Y-130500I-350J357D01*
G01X-911500D01*
Y-113500D01*
X-839500D01*
Y-130500D01*
X-846030D01*
G03X-846380Y-131357I0J-500D01*
G02X-848620I-1120J-1143D01*
G03X-848970Y-130500I-350J357D01*
G01X-871030D01*
G03X-871380Y-131357I0J-500D01*
G02X-873620I-1120J-1143D01*
G03X-873970Y-130500I-350J357D01*
G01X-896030D01*
G03X-896380Y-131357I0J-500D01*
G37*
G36*
G01X-1044690Y-49367D02*
X-1044718Y-49361D01*
X-1049600D01*
Y-48322D01*
X-1049619Y-48276D01*
G02Y-46946I1619J665D01*
G01X-1049600Y-46900D01*
Y-45589D01*
X-1050613D01*
X-1050654Y-45604D01*
G02X-1050782Y-45644I-546J1504D01*
G03X-1051005Y-46481I131J-483D01*
G01X-1050700Y-46786D01*
Y-50650D01*
X-1046669D01*
Y-51100D01*
X-1044425D01*
X-1043863Y-51663D01*
G02X-1045487Y-54607I-1237J-1237D01*
G01X-1045515Y-54600D01*
X-1046669D01*
Y-55050D01*
X-1050700D01*
Y-58414D01*
X-1052386Y-60100D01*
X-1063514D01*
X-1066000Y-57614D01*
Y-55400D01*
X-1066128D01*
Y-51400D01*
X-1066000D01*
Y-50500D01*
X-1058914D01*
X-1057400Y-48986D01*
Y-47286D01*
X-1055828Y-45714D01*
Y-42300D01*
X-1052628D01*
Y-42450D01*
X-1051813D01*
X-1051752Y-42389D01*
X-1049600D01*
Y-42239D01*
X-1046400D01*
Y-45861D01*
X-1043626D01*
X-1043063Y-46424D01*
G02X-1044690Y-49367I-1237J-1237D01*
G37*
G36*
G01X-179429Y-41944D02*
X-179400Y-41950D01*
X-178750D01*
Y-41789D01*
X-175550D01*
Y-45561D01*
X-173276D01*
X-172669Y-46169D01*
G02X-174408Y-48780I-1131J-1131D01*
G01X-174453Y-48761D01*
X-175550D01*
Y-48911D01*
X-179121D01*
Y-50150D01*
X-175091D01*
Y-50750D01*
X-172587D01*
X-172069Y-51269D01*
G02X-173568Y-53957I-1131J-1131D01*
G01X-173596Y-53950D01*
X-175091D01*
Y-54550D01*
X-179121D01*
Y-57914D01*
X-180807Y-59600D01*
X-191935D01*
X-194421Y-57114D01*
Y-54900D01*
X-194550D01*
Y-50900D01*
X-194421D01*
Y-50000D01*
X-187335D01*
X-185821Y-48486D01*
Y-46786D01*
X-184250Y-45214D01*
Y-41800D01*
X-181050D01*
Y-41950D01*
X-180200D01*
X-180171Y-41944D01*
G02X-179429I371J-1556D01*
G37*
G36*
G01X-489331Y-13953D02*
G02X-488610Y-13293I-670J1453D01*
G03X-488176Y-14041I434J-248D01*
G01X-484221D01*
Y-14400D01*
X-479121D01*
Y-12900D01*
X-464421D01*
Y-19100D01*
X-479121D01*
Y-17600D01*
X-484221D01*
Y-18041D01*
X-488621D01*
Y-14407D01*
G03X-489331Y-13953I-500J0D01*
G37*
G36*
G01X-302215Y-159743D02*
G02X-304400I-1093J-2304D01*
G03Y-158840I-214J452D01*
G02Y-154231I1093J2304D01*
G03Y-153328I-214J452D01*
G02Y-148720I1093J2304D01*
G03Y-147816I-214J452D01*
G02Y-143208I1093J2304D01*
G03Y-142304I-214J452D01*
G02Y-137696I1093J2304D01*
G03Y-136792I-214J452D01*
G02X-305224Y-136170I1093J2304D01*
G03X-306100Y-136499I-376J-330D01*
G01Y-138297D01*
X-308675Y-140872D01*
X-308691Y-140944D01*
G02X-310089Y-142698I-2490J550D01*
G03Y-143601I214J-452D01*
G02Y-148210I-1093J-2304D01*
G03Y-149113I214J-452D01*
G02Y-153721I-1093J-2304D01*
G03Y-154625I214J-452D01*
G02X-312274I-1093J-2304D01*
G03Y-153721I-214J452D01*
G02Y-149113I1093J2304D01*
G03Y-148210I-214J452D01*
G02X-313657Y-145297I1093J2304D01*
G01X-313624Y-145160D01*
X-316200Y-142584D01*
Y-141938D01*
G03X-317086Y-141620I-500J0D01*
G02X-317963Y-142304I-1969J1620D01*
G03Y-143208I214J-452D01*
G02X-321499Y-144784I-1093J-2304D01*
G01X-321456Y-144641D01*
X-323827Y-142270D01*
G03X-324681Y-142623I-354J-354D01*
G01Y-143638D01*
X-329181D01*
Y-141590D01*
G02Y-139197I2252J1197D01*
G01Y-136079D01*
G02Y-133685I2252J1197D01*
G01Y-131638D01*
X-324300D01*
Y-117697D01*
X-325700Y-116297D01*
Y-112103D01*
X-323297Y-109700D01*
X-314303D01*
X-312106Y-111897D01*
X-312010Y-111902D01*
G02X-312022Y-115098I-90J-1598D01*
G03X-312352Y-115951I24J-499D01*
G01X-306100Y-122203D01*
Y-132477D01*
G03X-305224Y-132807I500J0D01*
G02X-302215Y-136792I1917J-1682D01*
G03Y-137696I214J-452D01*
G02Y-142304I-1093J-2304D01*
G03Y-143208I214J-452D01*
G02Y-147816I-1093J-2304D01*
G03Y-148720I214J-452D01*
G02Y-153328I-1093J-2304D01*
G03Y-154231I214J-452D01*
G02Y-158840I-1093J-2304D01*
G03Y-159743I214J-452D01*
G37*
G36*
G01X-921026Y-158167D02*
G03X-921093Y-158738I373J-333D01*
G02X-923907I-1407J-762D01*
G03X-923974Y-158167I-440J238D01*
G01X-929500D01*
Y-158000D01*
X-930000D01*
Y-140000D01*
X-826000D01*
Y-158000D01*
X-828800D01*
Y-158167D01*
X-846026D01*
G03X-846093Y-158738I373J-333D01*
G02X-848907I-1407J-762D01*
G03X-848974Y-158167I-440J238D01*
G01X-871026D01*
G03X-871093Y-158738I373J-333D01*
G02X-873907I-1407J-762D01*
G03X-873974Y-158167I-440J238D01*
G01X-896026D01*
G03X-896093Y-158738I373J-333D01*
G02X-898907I-1407J-762D01*
G03X-898974Y-158167I-440J238D01*
G01X-921026D01*
G37*
G54D49*
X-1450000Y-112500D03*
X-1437500Y-175000D03*
X-1450000Y-162500D03*
Y-137500D03*
X-1437500Y-100000D03*
X-1436500Y-87500D03*
X-1450000D03*
X-1448900Y-76100D03*
X-1435000Y1000D03*
X-1425000Y-162500D03*
X-1430500Y-93500D03*
X-1430000Y-75400D03*
X-1421250Y-81250D03*
X-1431500Y-81000D03*
X-1419500Y-18000D03*
X-1412500Y-175000D03*
X-1406250Y-106250D03*
X-1412000Y-100500D03*
X-1418500Y-93500D03*
X-1406250Y-82500D03*
X-1412500Y-62500D03*
X-1387500Y-175000D03*
Y-150000D03*
X-1400000Y-162500D03*
X-1387500Y-125000D03*
X-1395000Y-106250D03*
X-1400000Y-112500D03*
X-1400500Y-96500D03*
X-1393750Y-82500D03*
X-1400000Y-75000D03*
X-1387500Y-62500D03*
X-1394500Y-18000D03*
X-1395000Y-500D03*
X-1371250Y-112500D03*
X-1380000Y-106250D03*
X-1381250Y-82500D03*
X-1375000Y-75000D03*
X-1373800Y-52900D03*
X-1382500Y-8000D03*
Y7000D03*
X-1363750Y-106250D03*
X-1356250Y-82500D03*
X-1368750D03*
X-1362500Y-62500D03*
X-1357500Y-8000D03*
X-1370000Y-500D03*
X-1357500Y7000D03*
X-1350600Y-75000D03*
X-1343200Y-82700D03*
X-1345000Y-500D03*
X-1330400Y-74900D03*
X-1337500Y-62500D03*
X-1332500Y-27500D03*
Y7000D03*
X-1321000Y-94850D03*
X-1293500Y-80000D03*
X-1257500Y-45000D03*
Y-20000D03*
X-1232500D03*
X-1202100Y-103200D03*
X-1199500Y-3000D03*
X-1154200Y-103100D03*
X-1151500Y-15000D03*
X-1137500D03*
X-1126000Y-2500D03*
X-1107700Y-73400D03*
Y-63100D03*
X-1107800Y-68200D03*
X-1111500Y-15000D03*
X-1099400Y-90200D03*
X-1093400D03*
X-1100000Y-2500D03*
X-1073000Y-90300D03*
X-997500Y-7500D03*
X-970000D03*
X-945000D03*
X-922500Y-132500D03*
Y-107500D03*
Y-82500D03*
Y-57500D03*
Y-7500D03*
X-910000Y-170000D03*
Y-95000D03*
Y-70000D03*
Y-45000D03*
Y-20000D03*
Y5000D03*
X-885000Y-170000D03*
X-897500Y-107500D03*
X-885000Y-95000D03*
X-897500Y-82500D03*
X-885000Y-70000D03*
X-897500Y-57500D03*
X-885000Y-45000D03*
Y-20000D03*
X-897500Y-7500D03*
X-885000Y5000D03*
X-872500Y-107500D03*
Y-82500D03*
Y-57500D03*
Y-7500D03*
X-860000Y-170000D03*
Y-95000D03*
Y-70000D03*
Y-45000D03*
Y-20000D03*
Y5000D03*
X-847500Y-107500D03*
Y-82500D03*
Y-57500D03*
Y-7500D03*
X-822500Y-159500D03*
Y-132500D03*
X-835000Y-120000D03*
X-822500Y-107500D03*
X-835000Y-95000D03*
X-822500Y-82500D03*
X-835000Y-70000D03*
X-822500Y-57500D03*
X-835000Y-45000D03*
X-822500Y-7500D03*
X-835000Y-20000D03*
X-810000D03*
Y5000D03*
X-797500Y-7500D03*
X-785000Y-20000D03*
Y5000D03*
X-760000Y-145000D03*
X-772500Y-132500D03*
X-760000Y-120000D03*
X-772500Y-107500D03*
X-760000Y-95000D03*
X-772500Y-82500D03*
X-760000Y-70000D03*
X-772500Y-57500D03*
X-760000Y-45000D03*
Y-20000D03*
X-772500Y-7500D03*
X-760000Y5000D03*
X-747500Y-57500D03*
Y-7500D03*
X-735000Y-45000D03*
Y-20000D03*
Y5000D03*
X-722500Y-57500D03*
Y-7500D03*
X-710000Y-45000D03*
X-697500Y-7500D03*
X-710000Y-20000D03*
Y5000D03*
X-685000Y-45000D03*
Y-20000D03*
Y5000D03*
X-672500Y-7500D03*
X-655500Y-25500D03*
X-642500D03*
Y-37500D03*
Y-12500D03*
X-630000Y-37500D03*
X-616000Y-25500D03*
X-602500Y-25000D03*
Y0D03*
X-590000Y-37500D03*
Y-12500D03*
Y12500D03*
X-577500Y-165000D03*
Y-140000D03*
Y-115000D03*
Y-65000D03*
Y-25000D03*
Y0D03*
X-565000Y-177500D03*
Y-152500D03*
Y-37500D03*
Y-12500D03*
Y12500D03*
X-540000Y-177500D03*
X-552500Y-165000D03*
X-540000Y-152500D03*
X-552500Y-140000D03*
X-540000Y-102500D03*
Y-77500D03*
X-552500Y-65000D03*
Y-25000D03*
X-540000Y-37500D03*
Y-12500D03*
X-552500Y0D03*
X-540000Y12500D03*
X-527500Y-165000D03*
Y-140000D03*
Y-115000D03*
Y-90000D03*
Y-65000D03*
Y-25000D03*
Y0D03*
X-515000Y-177500D03*
Y-152500D03*
Y-102500D03*
Y-77500D03*
Y-37500D03*
Y-12500D03*
Y12500D03*
X-490000Y-102500D03*
X-502500Y-90000D03*
X-490000Y-77500D03*
X-502500Y-65000D03*
X-490000Y-37500D03*
X-502500Y-25000D03*
Y0D03*
X-490000Y12500D03*
X-477500Y-25000D03*
Y0D03*
X-462000Y-73500D03*
X-465000Y-37500D03*
Y12500D03*
X-449000Y6500D03*
X-431000D03*
X-440000Y12500D03*
X-424500Y-26500D03*
X-374800Y-105700D03*
X-286500Y-113700D03*
X-296400Y-113500D03*
X-282300Y-113700D03*
X-196900Y-176500D03*
X-201600Y-176600D03*
X-206100D03*
G54D55*
X-793728Y-161850D03*
X-426181Y-175039D03*
X-434055D03*
X-426181Y-167165D03*
X-434055D03*
X-426181Y-159291D03*
X-434055D03*
X-426181Y-143543D03*
Y-135669D03*
X-434055D03*
X-426181Y-127795D03*
X-434055D03*
G54D52*
X-994488Y-93068D03*
Y-78108D03*
Y-63147D03*
Y-48187D03*
X-991535Y-98580D03*
Y-83620D03*
Y-68659D03*
Y-53698D03*
X-951181Y-93068D03*
X-948228Y-98580D03*
Y-83620D03*
X-951181Y-78108D03*
X-948228Y-68659D03*
X-951181Y-63147D03*
X-948228Y-53698D03*
X-951181Y-48187D03*
X-121457Y-98580D03*
X-124409Y-93068D03*
X-121457Y-83620D03*
X-124409Y-78108D03*
X-121457Y-68659D03*
X-124409Y-63147D03*
X-121457Y-53698D03*
X-124409Y-48187D03*
X-81102Y-93068D03*
Y-78108D03*
Y-63147D03*
Y-48187D03*
X-78150Y-98580D03*
Y-83620D03*
Y-68659D03*
Y-53698D03*
G54D54*
X-806854Y-83100D03*
G54D53*
Y-99635D03*
X-785200D03*
G54D51*
X-836000Y-172000D03*
Y500D03*
X-28500Y-169500D03*
Y500D03*
G54D48*
X-1410000Y0D03*
X0Y-136453D03*
X0Y0D03*
G54D50*
X-486810Y-167165D03*
X-1051613D03*
Y-118937D03*
X-486810D03*
X-181534Y-167165D03*
Y-118937D03*
G54D56*
X-785200Y-83100D03*
%LPD*%
G75*
G36*
G01X-1114950Y-134470D02*
X-1116000Y-133420D01*
Y-128500D01*
X-1115320Y-127820D01*
X-1113600D01*
X-1112970Y-128450D01*
Y-142400D01*
X-1114950D01*
Y-134470D01*
G37*
G36*
G01X-1109870Y-134440D02*
Y-142370D01*
X-1111850D01*
Y-128420D01*
X-1111220Y-127790D01*
X-1109710D01*
X-1109000Y-128500D01*
Y-133570D01*
X-1109870Y-134440D01*
G37*
G36*
G01X-1063100Y-59100D02*
X-1065000Y-57200D01*
Y-51500D01*
X-1058500D01*
X-1057800Y-50800D01*
X-1057628D01*
Y-50628D01*
X-1056400Y-49400D01*
Y-47700D01*
X-1055200Y-46500D01*
X-1052400D01*
X-1051700Y-47200D01*
Y-58000D01*
X-1052800Y-59100D01*
X-1063100D01*
G37*
G36*
G01X-1049650Y-31250D02*
X-1049150Y-31750D01*
Y-35600D01*
X-1054000D01*
X-1054750Y-34850D01*
X-1064000D01*
X-1064600Y-34250D01*
Y-24250D01*
X-1064000Y-23650D01*
X-1056500D01*
X-1051800Y-28350D01*
X-1049650D01*
Y-31250D01*
G37*
G36*
G01X-1064500Y-500D02*
X-1063650Y350D01*
X-1055000D01*
X-1052650Y-2000D01*
X-1051000D01*
X-1049550Y-3450D01*
Y-7250D01*
X-1049050Y-7750D01*
Y-11600D01*
X-1053900D01*
X-1054650Y-10850D01*
X-1064000D01*
X-1064500Y-10350D01*
Y-500D01*
G37*
G36*
G01X-309358Y-133099D02*
G03X-313229Y-133363I-1824J-1783D01*
G02X-313984Y-133418I-402J298D01*
G01X-320400Y-127003D01*
Y-114558D01*
G03X-320154Y-112814I-1200J1058D01*
G02X-319703Y-112100I452J214D01*
G01X-318397D01*
G02X-317946Y-112814I0J-500D01*
G03X-316684Y-115089I1446J-686D01*
G01X-316598Y-115099D01*
X-308500Y-123197D01*
Y-132750D01*
G02X-309358Y-133099I-500J0D01*
G37*
G36*
G01X-244890Y-134450D02*
X-245900Y-133440D01*
Y-128400D01*
X-245340Y-127840D01*
X-243500D01*
X-242910Y-128430D01*
Y-142420D01*
X-244890D01*
Y-134450D01*
G37*
G36*
G01X-239770Y-134460D02*
Y-142390D01*
X-241730D01*
Y-128420D01*
X-241120Y-127810D01*
X-239690D01*
X-238800Y-128700D01*
Y-133490D01*
X-239770Y-134460D01*
G37*
G36*
G01X-191521Y-58600D02*
X-193421Y-56700D01*
Y-51000D01*
X-186921D01*
X-186222Y-50300D01*
X-186050D01*
Y-50128D01*
X-184821Y-48900D01*
Y-47200D01*
X-183621Y-46000D01*
X-180821D01*
X-180121Y-46700D01*
Y-57500D01*
X-181221Y-58600D01*
X-191521D01*
G37*
G36*
G01X-182421Y-36100D02*
X-183171Y-35350D01*
X-193021D01*
Y-24150D01*
X-181871D01*
X-181761Y-24260D01*
Y-26100D01*
X-179921D01*
X-178071Y-27950D01*
Y-28500D01*
X-178100D01*
Y-31450D01*
X-178071D01*
Y-31750D01*
X-177571Y-32250D01*
Y-36100D01*
X-182421D01*
G37*
G36*
G01X-182321Y-11600D02*
X-182550Y-11372D01*
Y-10900D01*
X-183021D01*
X-183071Y-10850D01*
X-192921D01*
Y350D01*
X-181771D01*
X-177971Y-3450D01*
Y-7250D01*
X-177471Y-7750D01*
Y-11600D01*
X-182321D01*
G37*
G54D10*
X-1645906Y-167953D03*
X-1522728Y-154950D03*
X-1047676Y-78740D03*
X-652638Y-154950D03*
X-177597Y-78740D03*
X6890Y-167953D03*
G54D11*
X-1656906D03*
X-1645906Y-178953D03*
X-1653906Y-175453D03*
X-1653406Y-159953D03*
X-1645906Y-156953D03*
X-1634906Y-167953D03*
X-1637906Y-175453D03*
X-1638406Y-159953D03*
X-1530728Y-162450D03*
X-1533728Y-154950D03*
X-1530228Y-146950D03*
X-1522728Y-165950D03*
X-1514728Y-162450D03*
X-1515228Y-146950D03*
X-1522728Y-143950D03*
X-1511728Y-154950D03*
X-1058676Y-78740D03*
X-1047676Y-89740D03*
X-1055676Y-86240D03*
X-1055176Y-70740D03*
X-1047676Y-67740D03*
X-1039676Y-86240D03*
X-1040176Y-70740D03*
X-1036676Y-78740D03*
X-663638Y-154950D03*
X-652638Y-165950D03*
X-660638Y-162450D03*
X-660138Y-146950D03*
X-652638Y-143950D03*
X-641638Y-154950D03*
X-644638Y-162450D03*
X-645138Y-146950D03*
X-177597Y-89740D03*
X-185597Y-86240D03*
X-188597Y-78740D03*
X-185097Y-70740D03*
X-177597Y-67740D03*
X-169597Y-86240D03*
X-170097Y-70740D03*
X-166597Y-78740D03*
X-4110Y-167953D03*
X6890Y-178953D03*
X-1110Y-175453D03*
X14390Y-159953D03*
X-610D03*
X6890Y-156953D03*
X17890Y-167953D03*
X14890Y-175453D03*
G54D20*
X-1488693Y-178940D03*
X-1476693Y-64840D03*
X-618614Y-178940D03*
X-606614Y-64840D03*
G54D30*
X-1141240Y-132520D03*
Y-112835D03*
Y-94331D03*
X-1132087Y-150630D03*
X-1113189D03*
X-1094291D03*
X-1085138Y-132520D03*
Y-112835D03*
Y-94331D03*
X-271161Y-132520D03*
Y-112835D03*
Y-94331D03*
X-262008Y-150630D03*
X-243110D03*
X-224213D03*
X-215059Y-132520D03*
Y-112835D03*
Y-94331D03*
G54D21*
X-1484193Y-164390D03*
Y-169390D03*
X-1489193Y-164390D03*
Y-169390D03*
X-1494193Y-164390D03*
Y-169390D03*
X-1484193Y-149390D03*
Y-154390D03*
Y-159390D03*
X-1489193Y-149390D03*
Y-154390D03*
Y-159390D03*
X-1494193Y-149390D03*
Y-154390D03*
Y-159390D03*
X-1484193Y-134390D03*
Y-139390D03*
Y-144390D03*
X-1489193Y-134390D03*
Y-139390D03*
Y-144390D03*
X-1494193Y-134390D03*
Y-139390D03*
Y-144390D03*
X-1484193Y-119390D03*
Y-124390D03*
Y-129390D03*
X-1489193Y-119390D03*
Y-124390D03*
Y-129390D03*
X-1494193Y-119390D03*
Y-124390D03*
Y-129390D03*
X-1484193Y-104390D03*
Y-109390D03*
Y-114390D03*
X-1489193Y-104390D03*
Y-109390D03*
Y-114390D03*
X-1494193Y-104390D03*
Y-109390D03*
Y-114390D03*
X-1484193Y-89390D03*
Y-94390D03*
Y-99390D03*
X-1489193Y-89390D03*
Y-94390D03*
Y-99390D03*
X-1494193Y-89390D03*
Y-94390D03*
Y-99390D03*
X-1484193Y-74390D03*
Y-79390D03*
Y-84390D03*
X-1489193Y-74390D03*
Y-79390D03*
Y-84390D03*
X-1494193Y-74390D03*
Y-79390D03*
Y-84390D03*
X-1469193Y-164390D03*
Y-169390D03*
X-1474193Y-164390D03*
Y-169390D03*
X-1479193Y-164390D03*
Y-169390D03*
X-1469193Y-149390D03*
Y-154390D03*
Y-159390D03*
X-1474193Y-149390D03*
Y-154390D03*
Y-159390D03*
X-1479193Y-149390D03*
Y-154390D03*
Y-159390D03*
X-1469193Y-134390D03*
Y-139390D03*
Y-144390D03*
X-1474193Y-134390D03*
Y-139390D03*
Y-144390D03*
X-1479193Y-134390D03*
Y-139390D03*
Y-144390D03*
X-1469193Y-119390D03*
Y-124390D03*
Y-129390D03*
X-1474193Y-119390D03*
Y-124390D03*
Y-129390D03*
X-1479193Y-119390D03*
Y-124390D03*
Y-129390D03*
X-1469193Y-104390D03*
Y-109390D03*
Y-114390D03*
X-1474193Y-104390D03*
Y-109390D03*
Y-114390D03*
X-1479193Y-104390D03*
Y-109390D03*
Y-114390D03*
X-1469193Y-89390D03*
Y-94390D03*
Y-99390D03*
X-1474193Y-89390D03*
Y-94390D03*
Y-99390D03*
X-1479193Y-89390D03*
Y-94390D03*
Y-99390D03*
X-1469193Y-74390D03*
Y-79390D03*
Y-84390D03*
X-1474193Y-74390D03*
Y-79390D03*
Y-84390D03*
X-1479193Y-74390D03*
Y-79390D03*
Y-84390D03*
X-1459193Y-164390D03*
Y-169390D03*
X-1464193Y-164390D03*
Y-169390D03*
X-1459193Y-149390D03*
Y-154390D03*
Y-159390D03*
X-1464193Y-149390D03*
Y-154390D03*
Y-159390D03*
X-1459193Y-134390D03*
Y-139390D03*
Y-144390D03*
X-1464193Y-134390D03*
Y-139390D03*
Y-144390D03*
X-1459193Y-119390D03*
Y-124390D03*
Y-129390D03*
X-1464193Y-119390D03*
Y-124390D03*
Y-129390D03*
X-1459193Y-104390D03*
Y-109390D03*
Y-114390D03*
X-1464193Y-104390D03*
Y-109390D03*
Y-114390D03*
X-1459193Y-89390D03*
Y-94390D03*
Y-99390D03*
X-1464193Y-89390D03*
Y-94390D03*
Y-99390D03*
X-1459193Y-74390D03*
Y-79390D03*
Y-84390D03*
X-1464193Y-74390D03*
Y-79390D03*
Y-84390D03*
X-619114Y-164390D03*
Y-169390D03*
X-624114Y-164390D03*
Y-169390D03*
X-619114Y-149390D03*
Y-154390D03*
Y-159390D03*
X-624114Y-149390D03*
Y-154390D03*
Y-159390D03*
X-619114Y-134390D03*
Y-139390D03*
Y-144390D03*
X-624114Y-134390D03*
Y-139390D03*
Y-144390D03*
X-619114Y-119390D03*
Y-124390D03*
Y-129390D03*
X-624114Y-119390D03*
Y-124390D03*
Y-129390D03*
X-619114Y-104390D03*
Y-109390D03*
Y-114390D03*
X-624114Y-104390D03*
Y-109390D03*
Y-114390D03*
X-619114Y-89390D03*
Y-94390D03*
Y-99390D03*
X-624114Y-89390D03*
Y-94390D03*
Y-99390D03*
X-619114Y-74390D03*
Y-79390D03*
Y-84390D03*
X-624114Y-74390D03*
Y-79390D03*
Y-84390D03*
X-604114Y-164390D03*
Y-169390D03*
X-609114Y-164390D03*
Y-169390D03*
X-614114Y-164390D03*
Y-169390D03*
X-604114Y-149390D03*
Y-154390D03*
Y-159390D03*
X-609114Y-149390D03*
Y-154390D03*
Y-159390D03*
X-614114Y-149390D03*
Y-154390D03*
Y-159390D03*
X-604114Y-134390D03*
Y-139390D03*
Y-144390D03*
X-609114Y-134390D03*
Y-139390D03*
Y-144390D03*
X-614114Y-134390D03*
Y-139390D03*
Y-144390D03*
X-604114Y-119390D03*
Y-124390D03*
Y-129390D03*
X-609114Y-119390D03*
Y-124390D03*
Y-129390D03*
X-614114Y-119390D03*
Y-124390D03*
Y-129390D03*
X-604114Y-104390D03*
Y-109390D03*
Y-114390D03*
X-609114Y-104390D03*
Y-109390D03*
Y-114390D03*
X-614114Y-104390D03*
Y-109390D03*
Y-114390D03*
X-604114Y-89390D03*
Y-94390D03*
Y-99390D03*
X-609114Y-89390D03*
Y-94390D03*
Y-99390D03*
X-614114Y-89390D03*
Y-94390D03*
Y-99390D03*
X-604114Y-74390D03*
Y-79390D03*
Y-84390D03*
X-609114Y-74390D03*
Y-79390D03*
Y-84390D03*
X-614114Y-74390D03*
Y-79390D03*
Y-84390D03*
X-589114Y-164390D03*
Y-169390D03*
X-594114Y-164390D03*
Y-169390D03*
X-599114Y-164390D03*
Y-169390D03*
X-589114Y-149390D03*
Y-154390D03*
Y-159390D03*
X-594114Y-149390D03*
Y-154390D03*
Y-159390D03*
X-599114Y-149390D03*
Y-154390D03*
Y-159390D03*
X-589114Y-134390D03*
Y-139390D03*
Y-144390D03*
X-594114Y-134390D03*
Y-139390D03*
Y-144390D03*
X-599114Y-134390D03*
Y-139390D03*
Y-144390D03*
X-589114Y-119390D03*
Y-124390D03*
Y-129390D03*
X-594114Y-119390D03*
Y-124390D03*
Y-129390D03*
X-599114Y-119390D03*
Y-124390D03*
Y-129390D03*
X-589114Y-104390D03*
Y-109390D03*
Y-114390D03*
X-594114Y-104390D03*
Y-109390D03*
Y-114390D03*
X-599114Y-104390D03*
Y-109390D03*
Y-114390D03*
X-589114Y-89390D03*
Y-94390D03*
Y-99390D03*
X-594114Y-89390D03*
Y-94390D03*
Y-99390D03*
X-599114Y-89390D03*
Y-94390D03*
Y-99390D03*
X-589114Y-74390D03*
Y-79390D03*
Y-84390D03*
X-594114Y-74390D03*
Y-79390D03*
Y-84390D03*
X-599114Y-74390D03*
Y-79390D03*
Y-84390D03*
G54D12*
X-1656000Y-135000D03*
X-1658500Y-31000D03*
X-1639488Y-27500D03*
X-1644488D03*
X-1654488Y-27300D03*
X-1649488Y-27400D03*
X-1633000Y-135500D03*
X-1634488Y-27600D03*
X-1629488Y-27700D03*
X-1618400Y-71600D03*
X-1618300Y-63100D03*
X-1621600Y-61100D03*
Y-65100D03*
X-1618500Y-67200D03*
X-1621600Y-69400D03*
X-1615000Y-37500D03*
Y-27500D03*
Y-32500D03*
X-1610000Y-37500D03*
Y-32500D03*
Y-27500D03*
X-1600000Y-37500D03*
Y-27500D03*
Y-32500D03*
X-1605000Y-37500D03*
Y-32500D03*
Y-27500D03*
X-1595000Y-37500D03*
Y-32500D03*
Y-27500D03*
X-1580000Y-42500D03*
Y-47500D03*
X-1585000Y-42500D03*
Y-47500D03*
X-1590000D03*
Y-42500D03*
X-1580000Y-27500D03*
Y-32500D03*
Y-37500D03*
X-1585000Y-32500D03*
Y-27500D03*
Y-37500D03*
X-1590000D03*
Y-32500D03*
Y-27500D03*
X-1565000Y-42500D03*
Y-47500D03*
X-1575000Y-42500D03*
Y-47500D03*
X-1570000Y-42500D03*
Y-47500D03*
X-1565000Y-27500D03*
Y-32500D03*
Y-37500D03*
X-1575000Y-27500D03*
Y-32500D03*
Y-37500D03*
X-1570000Y-32500D03*
Y-27500D03*
Y-37500D03*
X-1555000Y-47500D03*
Y-42500D03*
X-1550000Y-47500D03*
Y-42500D03*
X-1560000D03*
Y-47500D03*
X-1545000D03*
Y-42500D03*
Y-37500D03*
Y-32500D03*
Y-27500D03*
X-1555000Y-37500D03*
Y-32500D03*
Y-27500D03*
X-1550000Y-37500D03*
Y-32500D03*
Y-27500D03*
X-1560000D03*
Y-32500D03*
Y-37500D03*
X-1530000Y-120300D03*
X-1535000Y-42500D03*
Y-47500D03*
X-1540000Y-42500D03*
Y-47500D03*
X-1535063Y-22160D03*
X-1540000Y-37500D03*
Y-32500D03*
X-1535000Y-37500D03*
Y-32500D03*
X-1530063Y-12160D03*
Y-17160D03*
Y-22160D03*
X-1535063Y-12160D03*
Y-17160D03*
X-1524359Y-125359D03*
X-1515063Y-12160D03*
Y-17160D03*
Y-22160D03*
X-1525063Y-12160D03*
Y-17160D03*
X-1520063Y-12160D03*
Y-17160D03*
X-1525063Y-22160D03*
X-1520063D03*
X-1497043Y-169390D03*
X-1500063Y-12160D03*
Y-17160D03*
Y-22160D03*
X-1510063Y-12160D03*
Y-17160D03*
X-1505063Y-12160D03*
Y-17160D03*
X-1510063Y-22160D03*
X-1505063D03*
X-1497043Y-164390D03*
X-1486693Y-166890D03*
X-1497043Y-149390D03*
X-1486693Y-161890D03*
X-1491652Y-151849D03*
X-1491693Y-156890D03*
X-1486693Y-151890D03*
Y-156890D03*
X-1497043Y-144390D03*
X-1491693Y-136890D03*
X-1486693Y-141890D03*
Y-146890D03*
Y-136890D03*
X-1497043Y-124390D03*
Y-129390D03*
X-1486693Y-121890D03*
Y-126890D03*
X-1491693Y-131890D03*
X-1486693D03*
X-1497043Y-109390D03*
Y-104390D03*
X-1486693Y-101890D03*
Y-106890D03*
X-1491693Y-111890D03*
Y-116890D03*
X-1486693Y-111890D03*
Y-116890D03*
X-1497043Y-89390D03*
X-1486693Y-86890D03*
X-1491693Y-91890D03*
Y-96890D03*
X-1486693Y-91890D03*
Y-96890D03*
Y-76890D03*
X-1491693D03*
X-1486693Y-81890D03*
X-1497000Y-81700D03*
X-1496693Y-76890D03*
Y-71890D03*
X-1486693D03*
X-1491693D03*
X-1485063Y-12160D03*
Y-17160D03*
Y-22160D03*
X-1495063Y-12160D03*
Y-17160D03*
X-1490063Y-12160D03*
Y-17160D03*
X-1495063Y-22160D03*
X-1490063D03*
X-1466693Y-166890D03*
X-1476693D03*
X-1471693D03*
X-1481693D03*
X-1476693Y-161890D03*
X-1481693Y-156890D03*
Y-151890D03*
X-1471693D03*
Y-156890D03*
X-1466693Y-161890D03*
Y-151890D03*
X-1476693D03*
X-1471693Y-161890D03*
X-1466693Y-156890D03*
X-1476693D03*
X-1481693Y-161890D03*
Y-136890D03*
X-1471693D03*
X-1466693Y-141890D03*
X-1476693D03*
X-1466693Y-146890D03*
X-1476693D03*
X-1471693Y-141890D03*
X-1466693Y-136890D03*
X-1476693D03*
X-1471693Y-146890D03*
X-1481693Y-141890D03*
Y-146890D03*
Y-131890D03*
X-1466693Y-121890D03*
X-1476693D03*
X-1466693Y-126890D03*
X-1476693D03*
X-1471693Y-131890D03*
X-1466693D03*
X-1471693Y-121890D03*
X-1476693Y-131890D03*
X-1471693Y-126890D03*
X-1481693Y-121890D03*
Y-126890D03*
Y-111890D03*
Y-116890D03*
X-1466693Y-101890D03*
X-1476693D03*
X-1466693Y-106890D03*
X-1476693D03*
X-1471693Y-111890D03*
Y-116890D03*
X-1466693Y-111890D03*
X-1471693Y-101890D03*
X-1476693Y-111890D03*
X-1466693Y-116890D03*
X-1471693Y-106890D03*
X-1476693Y-116890D03*
X-1481693Y-101890D03*
Y-106890D03*
Y-86890D03*
X-1471693D03*
X-1481693Y-91890D03*
Y-96890D03*
X-1466693Y-86890D03*
X-1476693D03*
X-1471693Y-91890D03*
Y-96890D03*
X-1476693Y-91890D03*
X-1466693D03*
X-1476693Y-96890D03*
X-1466693D03*
X-1481693Y-81890D03*
X-1471693D03*
X-1476693D03*
Y-71890D03*
X-1481693D03*
X-1471693D03*
X-1476693Y-76890D03*
X-1481693D03*
X-1471693D03*
X-1466693D03*
Y-81890D03*
Y-71890D03*
X-1475063Y-22160D03*
X-1470063Y-12160D03*
Y-17160D03*
Y-22160D03*
X-1480063Y-12160D03*
Y-17160D03*
X-1475063Y-12160D03*
Y-17160D03*
X-1480063Y-22160D03*
X-1461693Y-166890D03*
Y-151890D03*
Y-156890D03*
Y-161890D03*
Y-136890D03*
Y-141890D03*
Y-146890D03*
Y-131890D03*
Y-121890D03*
Y-126890D03*
X-1450000Y-112500D03*
X-1461693Y-111890D03*
Y-116890D03*
Y-101890D03*
Y-106890D03*
Y-86890D03*
Y-91890D03*
Y-96890D03*
Y-81890D03*
Y-71890D03*
X-1452000Y-74000D03*
X-1461693Y-76890D03*
X-1452000Y-78200D03*
X-1452100Y-82200D03*
X-1451700Y-65700D03*
X-1451500Y-61800D03*
X-1451800Y-69600D03*
X-1465063Y-12160D03*
Y-17160D03*
Y-22160D03*
X-1437500Y-175000D03*
X-1450000D03*
Y-162500D03*
X-1437500D03*
X-1450000Y-150000D03*
Y-137500D03*
Y-125000D03*
X-1437500Y-100000D03*
X-1436500Y-87500D03*
X-1450000D03*
X-1443500Y-94000D03*
X-1450000Y-100000D03*
X-1449100Y-71800D03*
X-1448900Y-76100D03*
X-1449000Y-80300D03*
X-1448800Y-63800D03*
X-1448700Y-59900D03*
X-1448800Y-67700D03*
X-1434892Y-40389D03*
Y-50389D03*
Y-45389D03*
Y-35389D03*
X-1435000Y1000D03*
X-1425000Y-175000D03*
Y-162500D03*
X-1430500Y-93500D03*
X-1424500Y-100000D03*
X-1425000Y-87500D03*
X-1430000Y-75400D03*
X-1421250Y-81250D03*
X-1431500Y-81000D03*
X-1425000Y-62500D03*
X-1419892Y-50389D03*
Y-40389D03*
Y-45389D03*
X-1427392Y-50389D03*
Y-45389D03*
Y-40389D03*
X-1419892Y-35389D03*
X-1427392D03*
X-1419500Y-18000D03*
X-1432000D03*
X-1420000Y14500D03*
X-1412500Y-175000D03*
Y-162500D03*
X-1406250Y-106250D03*
X-1412000Y-100500D03*
X-1418500Y-93500D03*
X-1412000Y-87000D03*
X-1406250Y-82500D03*
X-1412500Y-75000D03*
Y-62500D03*
X-1404892Y-50389D03*
Y-45389D03*
Y-40389D03*
X-1412392Y-50389D03*
Y-45389D03*
Y-40389D03*
X-1404892Y-35389D03*
X-1412392D03*
X-1407000Y-18000D03*
X-1407500Y14500D03*
X-1387500Y-175000D03*
X-1400000D03*
X-1387500Y-150000D03*
X-1400000Y-162500D03*
X-1387500D03*
X-1400000Y-150000D03*
X-1387300Y-133200D03*
X-1387500Y-137500D03*
Y-125000D03*
X-1400100Y-131550D03*
X-1400000Y-125000D03*
X-1395000Y-106250D03*
X-1400000Y-112500D03*
X-1387500D03*
X-1400500Y-96500D03*
Y-87000D03*
X-1391000Y-96500D03*
X-1393750Y-82500D03*
X-1400000Y-75000D03*
X-1387500D03*
Y-62500D03*
X-1400000D03*
X-1389892Y-40389D03*
Y-45389D03*
Y-50389D03*
X-1397392Y-40389D03*
Y-45389D03*
Y-50389D03*
X-1389892Y-35389D03*
X-1397392D03*
X-1394500Y-18000D03*
X-1395000Y-8000D03*
Y-500D03*
X-1395518Y14053D03*
X-1371250Y-112500D03*
X-1380000Y-106250D03*
X-1381250Y-82500D03*
X-1375000Y-75000D03*
Y-62500D03*
X-1373800Y-52900D03*
X-1382392Y-40389D03*
Y-45389D03*
Y-50389D03*
Y-35389D03*
X-1382500Y-8000D03*
Y-18000D03*
Y7000D03*
Y-500D03*
Y14500D03*
X-1363750Y-106250D03*
X-1356250Y-82500D03*
X-1368750D03*
X-1362500Y-75000D03*
Y-62500D03*
X-1356700Y-25600D03*
X-1357500Y-8000D03*
X-1370000D03*
Y-500D03*
X-1357500Y7000D03*
Y-500D03*
X-1370000Y7000D03*
Y14500D03*
X-1357500D03*
X-1350600Y-75000D03*
X-1343200Y-82700D03*
X-1350000Y-62500D03*
X-1345000Y-8000D03*
Y-500D03*
Y7000D03*
Y14500D03*
X-1330400Y-74900D03*
X-1324840Y-82120D03*
X-1335400Y-75000D03*
X-1337500Y-62500D03*
X-1324500Y-26959D03*
X-1332500Y-27500D03*
X-1335400Y-37600D03*
X-1332500Y7000D03*
Y-500D03*
Y14500D03*
X-1322228Y-88400D03*
X-1316728Y-89200D03*
X-1321000Y-94850D03*
X-1313040Y-80810D03*
X-1317700Y-72700D03*
X-1310559Y-74200D03*
X-1317700Y-60200D03*
X-1310559Y-68700D03*
Y-63200D03*
Y-57700D03*
X-1310600Y-46690D03*
X-1310559Y-41200D03*
Y-52200D03*
X-1311200Y-30200D03*
X-1310559Y-35700D03*
X-1320000Y-500D03*
Y7000D03*
X-1318500Y-6000D03*
X-1320000Y14500D03*
X-1306850Y-95000D03*
X-1300350Y-88500D03*
X-1293500Y-80000D03*
X-1302400Y-84100D03*
X-1297995Y-58405D03*
X-1298400Y-63200D03*
X-1298780Y-52200D03*
X-1298000Y-41200D03*
X-1298700Y-35700D03*
X-1298800Y-30200D03*
X-1295400Y-13400D03*
X-1307500Y7000D03*
X-1295000Y14500D03*
X-1307500D03*
X-1279429Y-180579D03*
X-1282500Y14500D03*
X-1269513Y-183637D03*
X-1266313D03*
X-1271813Y-181337D03*
X-1264267Y-181074D03*
X-1271813Y-185937D03*
X-1264013D03*
X-1276860Y-178030D03*
X-1263189Y-177998D03*
X-1272638D03*
X-1271088Y-151780D03*
X-1267888D03*
X-1274213Y-157350D03*
X-1264764D03*
X-1265588Y-154080D03*
X-1273388D03*
Y-149480D03*
X-1265588D03*
X-1261625Y-144435D03*
X-1263925Y-146735D03*
X-1264060Y-141950D03*
X-1270000Y14500D03*
X-1245710Y-189905D03*
Y-186705D03*
X-1248010Y-184405D03*
Y-192205D03*
X-1247979Y-177933D03*
X-1250591Y-179920D03*
X-1253740Y-177998D03*
X-1248860Y-150200D03*
X-1255315Y-157350D03*
X-1246390Y-153490D03*
X-1258425Y-144435D03*
X-1249016Y-144800D03*
X-1250660Y-140480D03*
X-1256125Y-146735D03*
Y-142135D03*
X-1257500Y-57500D03*
Y-45000D03*
Y-20000D03*
Y14500D03*
X-1232340Y-185380D03*
X-1235540D03*
X-1230040Y-183080D03*
Y-187680D03*
X-1237840Y-183080D03*
Y-187680D03*
X-1243410Y-184405D03*
Y-192205D03*
X-1237992Y-179850D03*
X-1234843Y-177998D03*
X-1241142Y-178998D03*
X-1244291Y-177998D03*
X-1236418Y-157350D03*
X-1236310Y-140390D03*
X-1230093Y-134350D03*
X-1233293D03*
X-1235593Y-136650D03*
Y-132050D03*
X-1245000Y-70000D03*
X-1232500Y-57500D03*
Y-45000D03*
X-1245000D03*
Y-20000D03*
X-1232500D03*
X-1245000Y14500D03*
X-1232500D03*
X-1215945Y-177998D03*
X-1225394D03*
X-1220590Y-149900D03*
X-1223790D03*
X-1217520Y-157350D03*
X-1226969D03*
X-1218290Y-152200D03*
X-1226090D03*
X-1218290Y-147600D03*
X-1226090D03*
X-1227793Y-136650D03*
Y-132050D03*
X-1220000Y14500D03*
X-1202580Y-176300D03*
X-1209420Y-167360D03*
X-1206220D03*
X-1211720Y-169660D03*
Y-165060D03*
X-1203920D03*
Y-169660D03*
X-1202100Y-103200D03*
X-1199500Y5400D03*
Y-3000D03*
X-1207500Y14500D03*
X-1191200Y-40500D03*
X-1191000Y-46500D03*
X-1191500Y-34000D03*
X-1191900Y-29500D03*
X-1190800Y-23450D03*
X-1191000Y-18250D03*
X-1191200Y-12128D03*
X-1192359Y-5800D03*
X-1191500Y0D03*
X-1195000Y14500D03*
X-1176100Y-114800D03*
X-1170300Y-114600D03*
X-1172500Y-44000D03*
X-1173200Y-49700D03*
X-1178900Y-46700D03*
X-1179000Y-40500D03*
X-1172500Y-38500D03*
X-1178950Y-23250D03*
X-1171800Y-26950D03*
X-1178800Y-34800D03*
X-1177800Y-12100D03*
X-1172000Y-10750D03*
X-1171500Y-21750D03*
X-1171800Y-16250D03*
X-1178800Y-5800D03*
X-1172100Y-5400D03*
X-1170000Y14500D03*
X-1182500D03*
X-1160000Y-115100D03*
X-1154200Y-103100D03*
X-1154400Y-107900D03*
X-1160000Y-38500D03*
X-1159700Y-43900D03*
X-1160150Y-26750D03*
X-1159800Y-33100D03*
X-1158700Y-16250D03*
X-1151500Y-15000D03*
X-1159700Y-5750D03*
X-1157500Y14500D03*
X-1137500Y-15000D03*
Y-2500D03*
X-1145000Y14500D03*
X-1124700Y-180000D03*
X-1124878Y-175150D03*
X-1124900Y-170650D03*
X-1134579Y-179850D03*
X-1123450Y-155183D03*
X-1120250D03*
X-1125750Y-152883D03*
Y-157483D03*
X-1126575Y-147990D03*
Y-136730D03*
X-1124800Y-129000D03*
X-1120400D03*
X-1125000Y-101700D03*
X-1121870Y-104330D03*
X-1128810Y-104171D03*
X-1126000Y-15000D03*
Y-2500D03*
X-1120000Y14500D03*
X-1132500D03*
X-1113328Y-182209D03*
X-1107828Y-182300D03*
X-1114979Y-170700D03*
X-1106979D03*
X-1117950Y-157483D03*
Y-152883D03*
X-1117126Y-136730D03*
X-1107677Y-148090D03*
Y-136730D03*
X-1117126Y-148090D03*
X-1108703Y-118455D03*
Y-121655D03*
X-1111003Y-123960D03*
X-1106403D03*
X-1114500Y-129000D03*
X-1110500D03*
X-1115490Y-104240D03*
X-1118701Y-101759D03*
X-1112402Y-101600D03*
X-1109300Y-104200D03*
X-1106102Y-102100D03*
X-1106403Y-116160D03*
X-1111003D03*
X-1107700Y-73400D03*
Y-63100D03*
X-1107800Y-68200D03*
X-1111500Y-15000D03*
Y-2500D03*
X-1107500Y14500D03*
X-1095600Y-179600D03*
X-1096278Y-170650D03*
X-1096200Y-175150D03*
X-1098228Y-148090D03*
Y-136730D03*
X-1102953Y-104200D03*
X-1099010Y-104183D03*
X-1099400Y-90200D03*
X-1093400D03*
X-1100000Y-15000D03*
Y-2500D03*
X-1095000Y14500D03*
X-1084600Y-179850D03*
X-1073000Y-90300D03*
X-1082500Y14500D03*
X-1056900Y-56300D03*
X-1063600Y-56600D03*
X-1062000Y-29200D03*
X-1061900Y-5200D03*
X-1070000Y14500D03*
X-1045100Y-52900D03*
X-1044300Y-47661D03*
X-1051200Y-44100D03*
X-1054900Y-29800D03*
X-1045400Y-38000D03*
X-1051400Y-26000D03*
X-1047289Y-26300D03*
X-1041300Y-10100D03*
Y-16500D03*
X-1054600Y-5100D03*
X-1050811Y2600D03*
X-1047300Y-2700D03*
X-1045000Y14500D03*
X-1033843Y-128576D03*
X-1032500Y14500D03*
X-1017670Y-123250D03*
X-1022140Y-122960D03*
X-1015729Y-100550D03*
X-1012638Y-85886D03*
X-1015179Y-74100D03*
X-1012638Y-70873D03*
Y-56060D03*
X-1012860Y-41250D03*
X-1012500Y-7500D03*
X-1020000Y14500D03*
X-1003380Y-86986D03*
X-1008429Y-91400D03*
X-999960Y-90706D03*
X-996670Y-75460D03*
X-1008719Y-75998D03*
X-999860Y-75848D03*
Y-60885D03*
X-1003780Y-56060D03*
X-994280Y-40890D03*
X-997500Y-7500D03*
X-1007500Y14500D03*
X-995000D03*
X-983000Y-7500D03*
X-982500Y14500D03*
X-969331Y-100849D03*
Y-85886D03*
X-965512Y-90706D03*
X-971779Y-73800D03*
X-965412Y-75848D03*
Y-45922D03*
X-970000Y-7500D03*
Y14500D03*
X-956653Y-90706D03*
X-960273Y-101049D03*
X-953250Y-75340D03*
X-956553Y-75848D03*
X-957779Y-57700D03*
X-956553Y-60885D03*
Y-45922D03*
X-957500Y-7500D03*
Y14500D03*
X-932500Y-7500D03*
X-945000D03*
X-932500Y14500D03*
X-945000D03*
X-922500Y-170000D03*
Y-159500D03*
Y-120000D03*
Y-132500D03*
Y-107500D03*
Y-95000D03*
Y-70000D03*
Y-82500D03*
Y-57500D03*
Y-45000D03*
Y-20000D03*
Y-7500D03*
Y5000D03*
X-922000Y14500D03*
X-910000Y-170000D03*
Y-159500D03*
Y-132500D03*
Y-107500D03*
Y-95000D03*
Y-82500D03*
Y-70000D03*
Y-57500D03*
Y-45000D03*
Y-7500D03*
Y-20000D03*
Y5000D03*
X-909500Y14500D03*
X-897500Y-170000D03*
X-885000D03*
Y-159500D03*
X-897500D03*
X-885000Y-132500D03*
X-897500D03*
X-885000Y-107500D03*
X-897500D03*
Y-95000D03*
X-885000D03*
Y-82500D03*
X-897500Y-70000D03*
Y-82500D03*
X-885000Y-70000D03*
Y-57500D03*
X-897500D03*
Y-45000D03*
X-885000D03*
Y-7500D03*
X-897500Y-20000D03*
X-885000D03*
X-897500Y-7500D03*
Y5000D03*
X-885000D03*
Y14500D03*
X-897500D03*
X-872500Y-170000D03*
Y-159500D03*
Y-132500D03*
Y-107500D03*
Y-95000D03*
Y-70000D03*
Y-82500D03*
Y-57500D03*
Y-45000D03*
Y-20000D03*
Y-7500D03*
Y5000D03*
Y14500D03*
X-860000Y-170000D03*
Y-159500D03*
Y-132500D03*
Y-107500D03*
Y-95000D03*
Y-82500D03*
Y-70000D03*
Y-57500D03*
Y-45000D03*
Y-7500D03*
Y-20000D03*
Y5000D03*
Y14500D03*
X-847500Y-170000D03*
Y-159500D03*
Y-132500D03*
Y-107500D03*
Y-95000D03*
Y-70000D03*
Y-82500D03*
Y-57500D03*
Y-45000D03*
Y-20000D03*
Y-7500D03*
Y5000D03*
X-848000Y14500D03*
X-822500Y-170000D03*
X-835000Y-159500D03*
X-822500D03*
Y-145000D03*
X-835000Y-132500D03*
X-822500Y-120000D03*
Y-132500D03*
X-835000Y-120000D03*
Y-107500D03*
X-822500D03*
Y-95000D03*
X-835000D03*
Y-82500D03*
X-822500Y-70000D03*
Y-82500D03*
X-835000Y-70000D03*
Y-57500D03*
X-822500D03*
Y-45000D03*
X-835000D03*
X-822500Y-20000D03*
Y-7500D03*
X-835000Y-20000D03*
X-822500Y5000D03*
X-835500Y14500D03*
X-822500D03*
X-810000Y-170000D03*
Y-157500D03*
Y-145000D03*
Y-132500D03*
Y-120000D03*
Y-70000D03*
Y-57500D03*
Y-45000D03*
Y-7500D03*
Y-20000D03*
Y5000D03*
Y14500D03*
X-797500Y-120000D03*
Y-70000D03*
Y-57500D03*
Y-45000D03*
Y-20000D03*
Y-7500D03*
Y5000D03*
Y14500D03*
X-785500Y-120000D03*
X-785000Y-70000D03*
Y-57500D03*
Y-45000D03*
Y-7500D03*
Y-20000D03*
Y5000D03*
Y14500D03*
X-772500Y-170000D03*
Y-145000D03*
X-760000D03*
Y-132500D03*
X-772500Y-120000D03*
Y-132500D03*
X-760000Y-120000D03*
Y-107500D03*
X-772500D03*
Y-95000D03*
X-760000D03*
Y-82500D03*
X-772500Y-70000D03*
Y-82500D03*
X-760000Y-70000D03*
Y-57500D03*
X-772500D03*
Y-45000D03*
X-760000D03*
Y-7500D03*
X-772500Y-20000D03*
X-760000D03*
X-772500Y-7500D03*
Y5000D03*
X-760000D03*
Y14500D03*
X-772500D03*
X-747500Y-57500D03*
Y-45000D03*
Y-20000D03*
Y-7500D03*
Y5000D03*
Y14500D03*
X-735000Y-57500D03*
Y-45000D03*
Y-7500D03*
Y-20000D03*
Y5000D03*
Y14500D03*
X-722500Y-57500D03*
Y-45000D03*
Y-20000D03*
Y-7500D03*
Y5000D03*
Y14500D03*
X-697500Y-45000D03*
X-710000D03*
X-697500Y-20000D03*
X-710000Y-7500D03*
X-697500D03*
X-710000Y-20000D03*
X-697500Y5000D03*
X-710000D03*
Y14500D03*
X-697500D03*
X-685000Y-45000D03*
Y-7500D03*
Y-20000D03*
Y5000D03*
Y14500D03*
X-672500Y-45000D03*
Y-20000D03*
Y-7500D03*
Y5000D03*
Y14500D03*
X-649700Y-117200D03*
X-655500Y-37500D03*
Y-25500D03*
Y-12500D03*
Y-500D03*
X-660000Y14500D03*
X-643700Y-125400D03*
X-642500Y-25500D03*
Y-37500D03*
Y-12500D03*
X-632500Y14500D03*
X-645000D03*
X-626964Y-169390D03*
Y-164390D03*
X-616614Y-166890D03*
X-621614Y-156890D03*
X-621573Y-151849D03*
X-616614Y-161890D03*
X-627200Y-151300D03*
X-616614Y-151890D03*
Y-156890D03*
X-621614Y-136890D03*
X-616614Y-146890D03*
Y-141890D03*
X-626900Y-141300D03*
X-616614Y-136890D03*
X-621614Y-131890D03*
X-616614Y-126890D03*
Y-121890D03*
X-621614D03*
X-628700Y-130100D03*
X-616614Y-131890D03*
X-621614Y-116890D03*
Y-111890D03*
X-626964Y-104390D03*
Y-109390D03*
X-616614Y-106890D03*
Y-101890D03*
Y-111890D03*
Y-116890D03*
X-621614Y-96890D03*
Y-91890D03*
X-626964Y-89390D03*
X-616614Y-86890D03*
Y-91890D03*
Y-96890D03*
Y-76890D03*
X-621614D03*
X-616614Y-81890D03*
X-626625Y-81614D03*
X-626614Y-76890D03*
Y-71890D03*
X-621614D03*
X-616614D03*
X-616000Y-37500D03*
X-630000Y-25500D03*
Y-37500D03*
X-616000Y-25500D03*
X-630000Y-12500D03*
X-616000D03*
Y14500D03*
X-606614Y-166890D03*
X-601614D03*
X-611614D03*
X-601614Y-156890D03*
Y-151890D03*
X-611614D03*
Y-156890D03*
X-606614Y-161890D03*
Y-151890D03*
X-601614Y-161890D03*
X-606614Y-156890D03*
X-611614Y-161890D03*
X-606614Y-146890D03*
Y-141890D03*
X-601614Y-136890D03*
X-611614D03*
X-601614Y-141890D03*
X-606614Y-136890D03*
X-601614Y-146890D03*
X-611614Y-141890D03*
Y-146890D03*
X-601614Y-131890D03*
X-606614Y-126890D03*
Y-121890D03*
X-611614Y-131890D03*
X-601614Y-121890D03*
X-606614Y-131890D03*
X-601614Y-126890D03*
X-611614Y-121890D03*
Y-126890D03*
X-601614Y-116890D03*
Y-111890D03*
X-606614Y-106890D03*
Y-101890D03*
X-611614Y-116890D03*
Y-111890D03*
X-601614Y-101890D03*
X-606614Y-111890D03*
X-601614Y-106890D03*
X-606614Y-116890D03*
X-611614Y-101890D03*
Y-106890D03*
Y-86890D03*
X-601614D03*
Y-96890D03*
Y-91890D03*
X-606614Y-86890D03*
X-611614Y-96890D03*
Y-91890D03*
X-606614D03*
Y-96890D03*
X-611614Y-81890D03*
X-601614D03*
X-606614D03*
Y-71890D03*
X-611614D03*
X-601614D03*
X-606614Y-76890D03*
X-611614D03*
X-601614D03*
X-602500Y-37500D03*
Y-25000D03*
Y-12500D03*
Y0D03*
Y12500D03*
X-596614Y-166890D03*
X-591614D03*
X-591200Y-179700D03*
X-591614Y-156890D03*
Y-151890D03*
X-596614Y-161890D03*
Y-151890D03*
X-591614Y-161890D03*
X-596614Y-156890D03*
X-591614Y-136890D03*
X-596614Y-146890D03*
Y-141890D03*
X-591614D03*
X-596614Y-136890D03*
X-591614Y-146890D03*
Y-131890D03*
X-596614Y-126890D03*
Y-121890D03*
X-591614D03*
X-596614Y-131890D03*
X-591614Y-126890D03*
Y-116890D03*
Y-111890D03*
X-596614Y-106890D03*
Y-101890D03*
Y-111890D03*
X-591614Y-101890D03*
X-596614Y-116890D03*
X-591614Y-106890D03*
Y-86890D03*
Y-96890D03*
Y-91890D03*
X-596614Y-86890D03*
Y-91890D03*
Y-96890D03*
X-591614Y-81890D03*
Y-71890D03*
X-596614Y-76890D03*
Y-81890D03*
X-591614Y-76890D03*
X-596614Y-71890D03*
X-590000Y-25000D03*
Y-37500D03*
Y-12500D03*
Y0D03*
Y12500D03*
X-577500Y-177500D03*
Y-165000D03*
Y-152500D03*
Y-140000D03*
Y-127500D03*
Y-115000D03*
Y-65000D03*
Y-37500D03*
Y-25000D03*
Y-12500D03*
Y0D03*
Y12500D03*
X-565000Y-165000D03*
Y-177500D03*
Y-152500D03*
Y-140000D03*
Y-65000D03*
Y-25000D03*
Y-37500D03*
Y-12500D03*
Y0D03*
Y12500D03*
X-540000Y-165000D03*
X-552500Y-177500D03*
X-540000D03*
X-552500Y-165000D03*
Y-152500D03*
X-540000D03*
Y-140000D03*
X-552500D03*
X-540000Y-127500D03*
Y-115000D03*
Y-102500D03*
Y-90000D03*
Y-77500D03*
Y-65000D03*
X-552500D03*
X-540000Y-25000D03*
X-552500Y-37500D03*
Y-25000D03*
X-540000Y-37500D03*
X-552500Y-12500D03*
X-540000D03*
Y0D03*
X-552500D03*
Y12500D03*
X-540000D03*
X-527500Y-177500D03*
Y-165000D03*
Y-152500D03*
Y-140000D03*
Y-127500D03*
Y-102500D03*
Y-115000D03*
Y-90000D03*
Y-77500D03*
Y-65000D03*
Y-37500D03*
Y-25000D03*
Y-12500D03*
Y0D03*
Y12500D03*
X-515000Y-165000D03*
Y-177500D03*
Y-152500D03*
Y-140000D03*
Y-127500D03*
Y-115000D03*
Y-102500D03*
Y-90000D03*
Y-77500D03*
Y-65000D03*
Y-25000D03*
Y-37500D03*
Y-12500D03*
Y0D03*
Y12500D03*
X-502500Y-102500D03*
X-490000D03*
Y-90000D03*
X-502500D03*
Y-77500D03*
X-490000D03*
X-502500Y-65000D03*
Y-37500D03*
X-490000D03*
X-502500Y-25000D03*
Y-12500D03*
X-490000D03*
Y0D03*
X-502500D03*
Y12500D03*
X-490000D03*
X-486421Y-26159D03*
X-477500Y-37500D03*
Y-25000D03*
Y0D03*
Y12500D03*
X-462000Y-73500D03*
X-465000Y-25000D03*
Y-37500D03*
X-461441Y6559D03*
X-465000Y12500D03*
X-453628Y-88300D03*
X-448128Y-88800D03*
X-456240Y-82020D03*
X-444440Y-80710D03*
X-452700Y-69000D03*
X-449100Y-60841D03*
X-442800Y-46600D03*
X-454421Y-26959D03*
X-443941Y6559D03*
X-449000Y6500D03*
X-448600Y-5900D03*
X-452500Y12500D03*
X-432118Y-87082D03*
X-436771Y-92400D03*
X-441959Y-74100D03*
X-429900Y-79600D03*
X-441959Y-68600D03*
X-429000Y-57600D03*
X-430700Y-63100D03*
X-441959D03*
Y-57600D03*
X-430180Y-52100D03*
X-429400Y-41100D03*
X-441959D03*
Y-52100D03*
X-430400Y-35600D03*
X-442000Y-29480D03*
X-441959Y-35600D03*
X-431000Y6500D03*
X-427500Y12500D03*
X-440000D03*
X-424500Y-26500D03*
X-424600Y-14400D03*
X-413500Y12500D03*
X-405540Y-183080D03*
X-399435Y-183637D03*
X-396235D03*
X-401735Y-181337D03*
Y-185937D03*
X-405540Y-179630D03*
X-402559Y-177998D03*
X-401009Y-151780D03*
X-397809D03*
X-403309Y-149480D03*
Y-154080D03*
X-395509Y-149480D03*
Y-154080D03*
X-404134Y-157350D03*
X-402500Y12500D03*
X-379521Y-181100D03*
X-394188Y-181074D03*
X-393935Y-185937D03*
X-383661Y-177998D03*
X-393110D03*
X-385237Y-157350D03*
X-394685D03*
X-380421Y-147000D03*
X-391547Y-144435D03*
X-388347D03*
X-393847Y-146735D03*
X-393981Y-141950D03*
X-386047Y-142135D03*
Y-146735D03*
X-389600Y-123640D03*
X-389770Y-127220D03*
X-386500Y-56500D03*
Y-44000D03*
Y-31500D03*
Y-19000D03*
Y-5500D03*
X-390000Y12500D03*
X-375631Y-189905D03*
Y-186705D03*
X-365461Y-185380D03*
X-367761Y-183080D03*
Y-187680D03*
X-377931Y-184405D03*
Y-192205D03*
X-373331D03*
Y-184405D03*
X-377900Y-177933D03*
X-367913Y-179850D03*
X-364764Y-177998D03*
X-371063Y-178998D03*
X-374213Y-177998D03*
X-366339Y-157350D03*
X-375800Y-154000D03*
X-365514Y-136650D03*
X-373620Y-124430D03*
X-365514Y-132050D03*
X-374800Y-105700D03*
X-374000Y-56500D03*
Y-44000D03*
Y-31500D03*
Y-19000D03*
X-365000Y12500D03*
X-377500D03*
X-362261Y-185380D03*
X-359961Y-183080D03*
Y-187680D03*
X-355315Y-177998D03*
X-350511Y-149900D03*
X-353711D03*
X-347441Y-157350D03*
X-356011Y-152200D03*
X-348211D03*
X-356890Y-157350D03*
X-360014Y-134350D03*
X-363214D03*
X-357714Y-136650D03*
X-356011Y-147600D03*
X-348211D03*
X-357714Y-132050D03*
X-360500Y-87100D03*
X-353700Y-87600D03*
X-361500Y-56500D03*
X-348000Y-57000D03*
X-361500Y-44000D03*
X-348000D03*
Y-31500D03*
X-361500D03*
Y-19000D03*
X-348000D03*
X-352500Y12500D03*
X-333450Y-174950D03*
X-339341Y-167360D03*
X-336141D03*
X-341641Y-169660D03*
Y-165060D03*
X-333841D03*
Y-169660D03*
X-345866Y-177998D03*
X-347850Y-87050D03*
X-342400Y-87500D03*
X-336000Y-53000D03*
Y-28000D03*
Y-15500D03*
X-340000Y12500D03*
X-321600Y-113500D03*
X-316500D03*
X-323500Y-65500D03*
X-321700Y-42000D03*
X-321500Y-47500D03*
X-322400Y-31000D03*
X-321300Y-24950D03*
X-321800Y-7300D03*
X-321700Y-13628D03*
X-321859Y-1500D03*
X-327500Y12500D03*
X-312100Y-113500D03*
X-303200Y-43300D03*
Y-48800D03*
X-309400Y-47700D03*
X-302300Y-25950D03*
X-302900Y-37900D03*
X-309400Y-25100D03*
X-308500Y-36400D03*
X-308800Y-7400D03*
X-302500Y-15200D03*
X-307900Y-13628D03*
X-302300Y-4450D03*
X-315000Y12500D03*
X-302500D03*
X-285000Y-107400D03*
Y-103100D03*
X-286500Y-113700D03*
X-296400Y-113500D03*
X-290400Y-43200D03*
X-289500Y-32500D03*
X-290800Y-26000D03*
X-290700Y-9750D03*
X-290300Y-4400D03*
X-290000Y12500D03*
X-274400Y-178200D03*
X-278100D03*
X-282300Y-113700D03*
X-277500Y12500D03*
X-254800Y-180000D03*
Y-170650D03*
X-254800Y-175150D03*
X-265200Y-179850D03*
X-255672Y-157483D03*
Y-152883D03*
X-256496Y-147990D03*
Y-136730D03*
X-254721Y-129000D03*
X-254921Y-101700D03*
X-258732Y-104171D03*
X-255500Y-25500D03*
X-268000Y-13000D03*
X-255500D03*
Y-500D03*
X-268000D03*
X-265000Y12500D03*
X-237750Y-182300D03*
X-243250Y-182209D03*
X-244900Y-170700D03*
X-253372Y-155183D03*
X-250172D03*
X-247872Y-152883D03*
Y-157483D03*
X-247047Y-148090D03*
Y-136730D03*
X-238624Y-118455D03*
Y-121655D03*
X-240924Y-123960D03*
X-250321Y-129000D03*
X-244300Y-129300D03*
X-240300D03*
X-245411Y-104240D03*
X-248622Y-101759D03*
X-251792Y-104330D03*
X-242323Y-101600D03*
X-239222Y-104200D03*
X-240924Y-116160D03*
X-243000Y-40500D03*
Y-25500D03*
Y-13000D03*
Y-500D03*
X-240000Y12500D03*
X-252500D03*
X-225400Y-179800D03*
X-226200Y-170650D03*
X-226121Y-175150D03*
X-236900Y-170700D03*
X-237598Y-136730D03*
X-228150D03*
Y-148090D03*
X-237598D03*
X-236324Y-123960D03*
X-236024Y-102100D03*
X-232874Y-104200D03*
X-236324Y-116160D03*
X-228932Y-104183D03*
X-230000Y-13500D03*
X-230500Y-500D03*
X-227500Y12500D03*
X-214500Y-179800D03*
X-215000Y12500D03*
X-196900Y-176500D03*
X-201600Y-176600D03*
X-206100D03*
X-191000Y-56400D03*
X-190300Y-28900D03*
Y-4200D03*
X-202500Y12500D03*
X-185900Y-56200D03*
X-179800Y-43500D03*
X-182900Y-29800D03*
X-176350Y-27200D03*
X-179811Y-21300D03*
X-183200Y-4600D03*
X-179011Y4500D03*
X-175100Y-1800D03*
X-177500Y12500D03*
X-190390Y12740D03*
X-163764Y-128576D03*
X-173800Y-47300D03*
X-173200Y-52400D03*
X-170200Y-34470D03*
X-170500Y-10000D03*
X-170300Y-16500D03*
X-165000Y12500D03*
X-150900Y-121100D03*
X-152400Y-125050D03*
X-145650Y-100550D03*
X-145100Y-74100D03*
X-152500Y12500D03*
X-138440Y-91390D03*
X-133301Y-86986D03*
X-142559Y-85886D03*
X-129882Y-90706D03*
X-129782Y-75998D03*
X-138640D03*
X-142559Y-70873D03*
X-133701Y-56060D03*
X-129782Y-60885D03*
X-142559Y-56060D03*
X-142130Y-41290D03*
X-139000Y-8500D03*
Y-21000D03*
X-140000Y12500D03*
X-127500D03*
X-126600Y-75410D03*
X-124590Y-41500D03*
X-114000Y-33500D03*
X-126500Y-21000D03*
X-114000Y-8500D03*
Y-21000D03*
X-126500Y-8500D03*
X-115000Y12500D03*
X-99252Y-100849D03*
Y-85886D03*
X-101700Y-73800D03*
X-101500Y-33500D03*
Y-21000D03*
Y-8500D03*
X-102500Y12500D03*
X-95433Y-90706D03*
X-86575D03*
X-90194Y-101049D03*
X-83310Y-75360D03*
X-95333Y-75848D03*
X-86475D03*
Y-60885D03*
X-87700Y-57700D03*
X-95333Y-45922D03*
X-86475D03*
X-89000Y-8500D03*
Y-21000D03*
X-90000Y12500D03*
X-74921Y-171500D03*
X-71500Y-158500D03*
Y-146000D03*
Y-133500D03*
X-71700Y-121000D03*
X-70500Y-108600D03*
X-76500Y-33500D03*
Y-21000D03*
Y-8500D03*
X-77500Y12500D03*
X-65000D03*
X-59500Y-173500D03*
Y-161000D03*
Y-136000D03*
Y-148500D03*
Y-123500D03*
Y-108500D03*
Y-96000D03*
Y-83500D03*
Y-71000D03*
Y-58500D03*
Y-46000D03*
Y-33500D03*
Y-8500D03*
Y-21000D03*
X-54500Y1500D03*
X-52500Y12500D03*
X-42500Y-173500D03*
X-43000Y-158500D03*
Y-146000D03*
X-47000Y-71000D03*
X-34500Y-83500D03*
Y-71000D03*
X-47000Y-83500D03*
X-34500Y-58500D03*
X-47000D03*
Y-46000D03*
X-34500D03*
Y-33500D03*
X-47000D03*
Y-21000D03*
X-34500Y-8500D03*
X-47000D03*
X-34500Y-21000D03*
X-42000Y1500D03*
X-40000Y12500D03*
X-18000Y-173500D03*
Y-158500D03*
X-30500D03*
Y-146000D03*
X-18000D03*
X-21150Y-83600D03*
X-22000Y-71000D03*
Y-58500D03*
Y-46000D03*
Y-33500D03*
Y-21000D03*
Y-8500D03*
X-27500Y12500D03*
X-9500Y-120000D03*
Y-108500D03*
Y-96000D03*
X-9350Y-83500D03*
X-9500Y-71000D03*
Y-58500D03*
Y-46000D03*
Y-33500D03*
Y-8500D03*
Y-21000D03*
X-17000Y1500D03*
X-2500Y12500D03*
X-15000D03*
X3000Y-120000D03*
Y-108500D03*
Y-96000D03*
Y-83500D03*
Y-71000D03*
Y-58500D03*
Y-46000D03*
Y-33500D03*
Y-21000D03*
Y-8500D03*
G54D40*
G01X-1183150Y-540000D02*
Y-552500D01*
G01X-1186485Y-540000D02*
X-1179815D01*
G01X-1171350Y-552500D02*
X-1172510Y-552292D01*
X-1173525Y-551459D01*
X-1174395Y-550208D01*
X-1174975Y-548750D01*
X-1175265Y-547083D01*
Y-545417D01*
X-1174975Y-543750D01*
X-1174395Y-542292D01*
X-1173525Y-541042D01*
X-1172510Y-540208D01*
X-1171350Y-540000D01*
X-1170190Y-540208D01*
X-1169175Y-541042D01*
X-1168305Y-542292D01*
X-1167725Y-543750D01*
X-1167435Y-545417D01*
Y-547083D01*
X-1167725Y-548750D01*
X-1168305Y-550208D01*
X-1169175Y-551459D01*
X-1170190Y-552292D01*
X-1171350Y-552500D01*
G01X-1162450D02*
Y-540000D01*
X-1158970D01*
X-1157810Y-540625D01*
X-1156940Y-542083D01*
X-1156650Y-543750D01*
X-1156940Y-545417D01*
X-1157665Y-546667D01*
X-1158970Y-547292D01*
X-1162450D01*
G01X-1138995Y-550834D02*
X-1137835Y-551875D01*
X-1136530Y-552500D01*
X-1135370D01*
X-1134210Y-551875D01*
X-1133340Y-550834D01*
X-1132905Y-549375D01*
X-1133195Y-547917D01*
X-1133920Y-546667D01*
X-1135225Y-545833D01*
X-1136965Y-545417D01*
X-1137980Y-544584D01*
X-1138415Y-543125D01*
X-1138125Y-541667D01*
X-1137400Y-540625D01*
X-1136385Y-540000D01*
X-1135370D01*
X-1134355Y-540417D01*
X-1133485Y-541458D01*
G01X-1125890Y-540000D02*
X-1122410D01*
G01X-1124150D02*
Y-552500D01*
G01X-1125890D02*
X-1122410D01*
G01X-1115540D02*
Y-540000D01*
X-1112640D01*
X-1111480Y-540625D01*
X-1110610Y-541458D01*
X-1109885Y-542708D01*
X-1109305Y-544167D01*
X-1109160Y-546250D01*
X-1109305Y-548333D01*
X-1109885Y-549792D01*
X-1110610Y-551042D01*
X-1111480Y-551875D01*
X-1112640Y-552500D01*
X-1115540D01*
G01X-1097650D02*
X-1103450D01*
Y-540000D01*
X-1097650D01*
G01X-1099970Y-546042D02*
X-1103450D01*
G01X-1089040Y-554792D02*
X-1088460Y-552083D01*
G01X-1068050Y-540000D02*
Y-552500D01*
X-1062250D01*
G01X-1056975D02*
X-1053350Y-540000D01*
X-1049725Y-552500D01*
G01X-1051030Y-548125D02*
X-1055670D01*
G01X-1041550Y-552500D02*
Y-546875D01*
X-1044450Y-540000D01*
G01X-1038650D02*
X-1041550Y-546875D01*
G01X-1026850Y-552500D02*
X-1032650D01*
Y-540000D01*
X-1026850D01*
G01X-1029170Y-546042D02*
X-1032650D01*
G01X-1020850Y-552500D02*
Y-540000D01*
X-1017225D01*
X-1016065Y-540625D01*
X-1015340Y-541458D01*
X-1015050Y-543125D01*
X-1015340Y-544792D01*
X-1016210Y-545833D01*
X-1017225Y-546458D01*
X-1020850D01*
G01X-1017225D02*
X-1015050Y-552500D01*
G01X-994350D02*
Y-540000D01*
X-996090Y-542500D01*
G01Y-552500D02*
X-992610D01*
G54D31*
X-1141240Y-142362D03*
Y-102992D03*
Y-63622D03*
Y-24252D03*
X-1128760Y-83307D03*
X-1118917Y-4567D03*
X-1107500Y-83307D03*
X-1085138Y-122677D03*
Y-83307D03*
Y-43937D03*
Y-4567D03*
X-785200Y-83100D03*
X-271161Y-142362D03*
Y-102992D03*
Y-63622D03*
Y-24252D03*
X-258681Y-83307D03*
X-237421D03*
X-248839Y-4567D03*
X-215059Y-122677D03*
Y-83307D03*
Y-43937D03*
Y-4567D03*
G54D22*
X-1410000Y0D03*
X-1356889Y-167165D03*
Y-118937D03*
X-1312008Y-149449D03*
X-1278150Y-142362D03*
X-1212008D03*
X-1132087Y-126220D03*
X-1094291D03*
X-1051613Y-167165D03*
Y-118937D03*
X-486810Y-167165D03*
Y-118937D03*
X-441929Y-149449D03*
X-408071Y-142362D03*
X-341929D03*
X-262008Y-126220D03*
X-224213D03*
X-181534Y-167165D03*
Y-118937D03*
X0Y-136453D03*
X0Y0D03*
G54D13*
X-1646000Y-140700D03*
X-836000Y-172000D03*
Y500D03*
X-28500Y-169500D03*
Y500D03*
G54D41*
G01X-1317700Y-69059D02*
Y-72700D01*
G01X-1307559Y-74200D02*
X-1310559D01*
G01X-1307559Y-63200D02*
X-1310559D01*
G01X-1307559Y-57700D02*
X-1310559D01*
G01X-1307559Y-41200D02*
X-1310559D01*
G01X-1307559Y-52200D02*
X-1310559D01*
G01X-1307559Y-35700D02*
X-1310559D01*
G01X-1185925Y-592500D02*
X-1178575Y-577500D01*
G01X-1185925D02*
X-1178575Y-592500D01*
G01X-1168050D02*
X-1166825Y-592250D01*
X-1165425Y-591500D01*
X-1164550Y-590250D01*
X-1164200Y-588500D01*
X-1164550Y-586750D01*
X-1165600Y-585250D01*
X-1167175Y-584500D01*
X-1168925D01*
X-1169975Y-584000D01*
X-1170850Y-582750D01*
X-1171200Y-581000D01*
X-1170675Y-579250D01*
X-1169450Y-578000D01*
X-1168050Y-577500D01*
X-1166650Y-578000D01*
X-1165425Y-579250D01*
X-1164900Y-581000D01*
X-1165250Y-582750D01*
X-1166125Y-584000D01*
X-1167175Y-584500D01*
X-1168925D01*
X-1170500Y-585250D01*
X-1171550Y-586750D01*
X-1171900Y-588500D01*
X-1171550Y-590250D01*
X-1170675Y-591500D01*
X-1169275Y-592250D01*
X-1168050Y-592500D01*
G01X-1153850D02*
X-1152625Y-592250D01*
X-1151225Y-591500D01*
X-1150350Y-590250D01*
X-1150000Y-588500D01*
X-1150350Y-586750D01*
X-1151400Y-585250D01*
X-1152975Y-584500D01*
X-1154725D01*
X-1155775Y-584000D01*
X-1156650Y-582750D01*
X-1157000Y-581000D01*
X-1156475Y-579250D01*
X-1155250Y-578000D01*
X-1153850Y-577500D01*
X-1152450Y-578000D01*
X-1151225Y-579250D01*
X-1150700Y-581000D01*
X-1151050Y-582750D01*
X-1151925Y-584000D01*
X-1152975Y-584500D01*
X-1154725D01*
X-1156300Y-585250D01*
X-1157350Y-586750D01*
X-1157700Y-588500D01*
X-1157350Y-590250D01*
X-1156475Y-591500D01*
X-1155075Y-592250D01*
X-1153850Y-592500D01*
G01X-1140000D02*
X-1139650Y-589250D01*
X-1139125Y-586500D01*
X-1138425Y-584000D01*
X-1137550Y-581250D01*
X-1136150Y-577500D01*
X-1143150D01*
G01X-1129300Y-590250D02*
X-1128250Y-591500D01*
X-1127025Y-592250D01*
X-1125450Y-592500D01*
X-1123875Y-592000D01*
X-1122650Y-591000D01*
X-1121775Y-589250D01*
X-1121600Y-587250D01*
X-1121950Y-585250D01*
X-1122825Y-584000D01*
X-1124050Y-583000D01*
X-1125275Y-582750D01*
X-1126500Y-583000D01*
X-1128075Y-584000D01*
X-1127550Y-577500D01*
X-1122825D01*
G01X-1111600Y-592500D02*
X-1111250Y-589250D01*
X-1110725Y-586500D01*
X-1110025Y-584000D01*
X-1109150Y-581250D01*
X-1107750Y-577500D01*
X-1114750D01*
G01X-1097050Y-592500D02*
Y-577500D01*
X-1099150Y-580500D01*
G01Y-592500D02*
X-1094950D01*
G01X-1085125Y-587500D02*
X-1080575D01*
G01X-1068650Y-577500D02*
X-1070050Y-578000D01*
X-1071100Y-579250D01*
X-1071800Y-580750D01*
X-1072325Y-582750D01*
X-1072500Y-585000D01*
X-1072325Y-587250D01*
X-1071800Y-589250D01*
X-1071100Y-590750D01*
X-1070050Y-592000D01*
X-1068650Y-592500D01*
X-1067250Y-592000D01*
X-1066200Y-590750D01*
X-1065500Y-589250D01*
X-1064975Y-587250D01*
X-1064800Y-585000D01*
X-1064975Y-582750D01*
X-1065500Y-580750D01*
X-1066200Y-579250D01*
X-1067250Y-578000D01*
X-1068650Y-577500D01*
G01X-1054450D02*
X-1055850Y-578000D01*
X-1056900Y-579250D01*
X-1057600Y-580750D01*
X-1058125Y-582750D01*
X-1058300Y-585000D01*
X-1058125Y-587250D01*
X-1057600Y-589250D01*
X-1056900Y-590750D01*
X-1055850Y-592000D01*
X-1054450Y-592500D01*
X-1053050Y-592000D01*
X-1052000Y-590750D01*
X-1051300Y-589250D01*
X-1050775Y-587250D01*
X-1050600Y-585000D01*
X-1050775Y-582750D01*
X-1051300Y-580750D01*
X-1052000Y-579250D01*
X-1053050Y-578000D01*
X-1054450Y-577500D01*
G01X-1044100Y-590250D02*
X-1043050Y-591500D01*
X-1041825Y-592250D01*
X-1040250Y-592500D01*
X-1038675Y-592000D01*
X-1037450Y-591000D01*
X-1036575Y-589250D01*
X-1036400Y-587250D01*
X-1036750Y-585250D01*
X-1037625Y-584000D01*
X-1038850Y-583000D01*
X-1040075Y-582750D01*
X-1041300Y-583000D01*
X-1042875Y-584000D01*
X-1042350Y-577500D01*
X-1037625D01*
G01X-1187359Y-29400D02*
X-1191800D01*
X-1191900Y-29500D01*
G01X-1187487Y-23450D02*
X-1190800D01*
G01X-1187409Y-12128D02*
X-1191200D01*
G01X-1187359Y0D02*
X-1191500D01*
G01X-1168487Y-26950D02*
X-1171800D01*
G01X-1168487Y-16250D02*
X-1171800D01*
G01X-1168487Y-5450D02*
X-1172050D01*
X-1172100Y-5400D01*
G01X-1163441Y-44000D02*
X-1159800D01*
X-1159700Y-43900D01*
G01X-1163441Y-49500D02*
Y-44000D01*
G01Y-33000D02*
X-1159900D01*
X-1159800Y-33100D01*
G01X-1113328Y-179209D02*
Y-182209D01*
G01X-1107828Y-179209D02*
Y-182300D01*
G01X-1088489Y-179700D02*
X-1084750D01*
X-1084600Y-179850D01*
G01X-1048669Y-52850D02*
X-1045150D01*
X-1045100Y-52900D01*
G01X-1048000Y-47611D02*
X-1044350D01*
X-1044300Y-47661D01*
G01X-1045441Y-34000D02*
Y-37959D01*
X-1045400Y-38000D01*
G01X-1050911Y-23000D02*
Y-25511D01*
X-1051400Y-26000D01*
G01X-1045441Y-10000D02*
X-1041400D01*
X-1041300Y-10100D01*
G01X-1045550Y-16600D02*
X-1041400D01*
X-1041300Y-16500D01*
G01X-1050811Y0D02*
Y2600D01*
G01X-1047200Y-5400D02*
Y-2800D01*
X-1047300Y-2700D01*
G01D02*
X-1047189Y-2589D01*
Y0D01*
G01X-911875Y-592500D02*
X-907500Y-577500D01*
X-903125Y-592500D01*
G01X-904700Y-587250D02*
X-910300D01*
G01X-810781Y-103562D02*
X-806854Y-99635D01*
G01D02*
X-802927Y-95708D01*
G01X-810781D02*
X-806854Y-99635D01*
G01D02*
X-802927Y-103562D01*
G01X-796771Y-141271D02*
X-793728Y-138228D01*
G01D02*
X-790685Y-135185D01*
G01X-796771D02*
X-793728Y-138228D01*
G01D02*
X-790685Y-141271D01*
G01X-789127Y-103562D02*
X-785200Y-99635D01*
G01X-789127Y-95708D02*
X-785200Y-99635D01*
G01D02*
X-781273Y-103562D01*
G01X-785200Y-99635D02*
X-781273Y-95708D01*
G01X-535500Y-127350D02*
X-539850D01*
X-540000Y-127500D01*
G01X-519200Y-127300D02*
X-515200D01*
X-515000Y-127500D01*
G01X-449100Y-63841D02*
Y-60841D01*
G01X-438959Y-74100D02*
X-441959D01*
G01X-438959Y-63100D02*
X-441959D01*
G01X-438959Y-57600D02*
X-441959D01*
G01X-438959Y-41100D02*
X-441959D01*
G01X-438959Y-52100D02*
X-441959D01*
G01X-438959Y-35600D02*
X-441959D01*
G01X-317859Y-30900D02*
X-322300D01*
X-322400Y-31000D01*
G01X-317987Y-24950D02*
X-321300D01*
G01X-317909Y-13628D02*
X-321700D01*
G01X-298987Y-25950D02*
X-302300D01*
G01X-299259Y-38000D02*
X-302800D01*
X-302900Y-37900D01*
G01X-298987Y-4450D02*
X-302300D01*
G01X-294141Y-48800D02*
Y-43300D01*
G01D02*
X-290500D01*
X-290400Y-43200D01*
G01X-294013Y-9750D02*
X-290700D01*
G01X-243250Y-179209D02*
Y-182209D01*
G01X-237750Y-179209D02*
Y-182300D01*
G54D23*
X-1391300Y-133200D03*
Y-136800D03*
X-1322228Y-85650D03*
Y-82050D03*
X-1059228Y-49050D03*
Y-52650D03*
X-1054228Y-44050D03*
Y-47650D03*
X-1048000Y-47611D03*
Y-43989D03*
X-1056000Y-37300D03*
Y-33700D03*
Y-13300D03*
Y-9700D03*
X-519200Y-123700D03*
Y-127300D03*
X-453628Y-85550D03*
Y-81950D03*
X-187650Y-48550D03*
Y-52150D03*
X-182650Y-43550D03*
Y-47150D03*
X-177150Y-47161D03*
Y-43539D03*
X-184150Y-38150D03*
Y-34550D03*
Y-12650D03*
Y-9050D03*
G54D32*
X-1122128Y-170650D03*
Y-175150D03*
X-1121800Y-180000D03*
X-1127689Y-179900D03*
X-1131311D03*
X-1118528Y-170650D03*
Y-175150D03*
X-1118200Y-180000D03*
X-1099028Y-175150D03*
X-1102628D03*
X-1099028Y-170650D03*
X-1102628D03*
X-1099028Y-179650D03*
X-1102628D03*
X-1088489Y-179700D03*
X-1092111D03*
X-1050800Y-29400D03*
X-1047200D03*
X-1047289Y-23000D03*
X-1050911D03*
X-1050800Y-5400D03*
X-1047200D03*
X-1047189Y0D03*
X-1050811D03*
X-257889Y-180000D03*
X-261511D03*
X-252050Y-170650D03*
X-248450D03*
X-252050Y-175150D03*
X-248450D03*
X-248100Y-180000D03*
X-251700D03*
X-228950Y-175150D03*
X-232550D03*
X-228950Y-170650D03*
X-232550D03*
X-228950Y-179650D03*
X-232550D03*
X-222011Y-179900D03*
X-218389D03*
X-179950Y-29850D03*
X-176350D03*
X-176389Y-24500D03*
X-180011D03*
X-178800Y-4500D03*
X-175200D03*
X-175189Y1000D03*
X-178811D03*
G54D14*
X-1649000Y-121500D03*
Y-105752D03*
Y-113626D03*
Y-97878D03*
X-1327756Y-175039D03*
Y-167165D03*
Y-159291D03*
Y-143543D03*
Y-135669D03*
X-1319882Y-175039D03*
Y-167165D03*
Y-159291D03*
Y-143543D03*
Y-135669D03*
Y-127795D03*
X-1296260Y-175039D03*
X-1304134D03*
X-1296260Y-167165D03*
X-1304134D03*
X-1296260Y-159291D03*
X-1304134D03*
X-1296260Y-143543D03*
X-1304134D03*
X-1296260Y-135669D03*
X-1304134D03*
X-1296260Y-127795D03*
X-1304134D03*
X-793728Y-161850D03*
Y-153976D03*
Y-138228D03*
Y-146102D03*
X-457677Y-175039D03*
Y-167165D03*
Y-159291D03*
Y-143543D03*
Y-135669D03*
X-449803Y-175039D03*
Y-167165D03*
Y-159291D03*
Y-143543D03*
Y-135669D03*
Y-127795D03*
X-426181Y-175039D03*
X-434055D03*
X-426181Y-167165D03*
X-434055D03*
X-426181Y-159291D03*
X-434055D03*
X-426181Y-143543D03*
X-434055D03*
X-426181Y-135669D03*
X-434055D03*
X-426181Y-127795D03*
X-434055D03*
G54D42*
G01X-1618400Y-71600D02*
X-1618500Y-71500D01*
X-1624940D01*
X-1628040Y-68400D01*
Y-58310D01*
X-1626410Y-56680D01*
Y-38790D01*
X-1637100Y-28100D01*
Y-26892D01*
X-1654488Y-9504D01*
Y7244D01*
G01X-1644488D02*
Y-11812D01*
X-1631400Y-24900D01*
Y-28800D01*
X-1623990Y-36210D01*
Y-57390D01*
X-1625760Y-59160D01*
Y-65260D01*
X-1623820Y-67200D01*
X-1618500D01*
G01X-1649488Y7244D02*
Y-9112D01*
X-1632600Y-26000D01*
Y-30400D01*
X-1625250Y-37750D01*
Y-57010D01*
X-1626900Y-58660D01*
Y-67090D01*
X-1624590Y-69400D01*
X-1621600D01*
G01Y-65100D02*
X-1622800D01*
X-1624680Y-63220D01*
Y-59550D01*
X-1622680Y-57550D01*
Y-30720D01*
X-1639488Y-13912D01*
Y7244D01*
G01X-1618300Y-63100D02*
X-1622710D01*
X-1623620Y-62190D01*
Y-60130D01*
X-1621490Y-58000D01*
Y-29710D01*
X-1634488Y-16712D01*
Y7244D01*
G01X-1629488D02*
Y-19212D01*
X-1620320Y-28380D01*
Y-58420D01*
X-1621600Y-59700D01*
Y-61100D01*
G01X-1519000Y-120241D02*
X-1529941D01*
X-1530000Y-120300D01*
G01X-1330350Y-6000D02*
X-1318500D01*
G01X-1317700Y-63941D02*
Y-60200D01*
G01X-1307559Y-68700D02*
X-1310559D01*
G01X-1307559Y-30200D02*
X-1311200D01*
G01X-1300350Y-88500D02*
X-1302500D01*
X-1306850Y-92850D01*
Y-95000D01*
G01X-1302441Y-68700D02*
Y-74200D01*
G01D02*
Y-79700D01*
G01X-1302400Y-84100D02*
X-1302441Y-84059D01*
Y-79700D01*
G01Y-57700D02*
X-1298700D01*
X-1297995Y-58405D01*
G01X-1302441Y-63200D02*
X-1298400D01*
G01X-1298780Y-52200D02*
X-1302441D01*
G01Y-46700D02*
Y-52200D01*
G01Y-41200D02*
X-1298000D01*
G01X-1298700Y-35700D02*
X-1302441D01*
G01X-1299550Y-6900D02*
X-1295800D01*
X-1295400Y-7300D01*
Y-13400D01*
G01X-1247441Y-172598D02*
Y-177395D01*
X-1247979Y-177933D01*
G01X-1250591Y-172598D02*
Y-179920D01*
G01X-1242717Y-162756D02*
Y-151920D01*
X-1244437Y-150200D01*
X-1248860D01*
G01X-1249016Y-162756D02*
X-1249070Y-162702D01*
Y-154190D01*
X-1251170Y-152090D01*
Y-148700D01*
X-1249016Y-146546D01*
Y-144800D01*
G01X-1252165Y-162756D02*
Y-154950D01*
X-1252570Y-154545D01*
Y-144690D01*
X-1250660Y-142780D01*
Y-140480D01*
G01X-1237992Y-179850D02*
Y-172598D01*
G01X-1239567Y-162756D02*
Y-156957D01*
X-1236310Y-153700D01*
Y-140390D01*
G01X-1200000Y-560000D02*
X-890000D01*
G01Y-520000D02*
X-1200000D01*
G01X-575000Y-480000D02*
X-1200000D01*
G01X-1176100Y-114800D02*
X-1184900Y-123600D01*
Y-142300D01*
X-1181294Y-145906D01*
X-1181260D01*
G01X-1187559Y-40500D02*
X-1191200D01*
G01X-1187559Y-46500D02*
X-1191000D01*
G01X-1187359Y-5800D02*
X-1192359D01*
G01X-1160000Y-115100D02*
X-1161200D01*
X-1175800Y-129700D01*
Y-137586D01*
X-1173386Y-140000D01*
G01X-1154400Y-107900D02*
Y-112200D01*
X-1169100Y-126900D01*
Y-136624D01*
X-1165512Y-140212D01*
Y-140394D01*
G01X-1170300Y-114600D02*
Y-121100D01*
X-1177900Y-128700D01*
Y-137000D01*
X-1181260Y-140360D01*
Y-140394D01*
G01X-1168559Y-44000D02*
X-1172500D01*
G01X-1173200Y-49700D02*
X-1170900D01*
X-1170700Y-49500D01*
X-1168559D01*
G01X-1182441Y-46500D02*
X-1179100D01*
X-1178900Y-46700D01*
G01X-1182369Y-18250D02*
Y-23450D01*
G01X-1178950Y-23250D02*
X-1182169D01*
X-1182369Y-23450D01*
G01X-1168559Y-33000D02*
Y-38500D01*
G01D02*
X-1172500D01*
G01X-1182241Y-29400D02*
Y-34900D01*
G01D02*
X-1178900D01*
X-1178800Y-34800D01*
G01X-1182291Y-12128D02*
X-1177828D01*
X-1177800Y-12100D01*
G01X-1182241Y-5800D02*
Y0D01*
G01Y-5800D02*
X-1178800D01*
G01X-1160150Y-26750D02*
X-1163369D01*
G01D02*
Y-26950D01*
G01Y-26750D02*
Y-21750D01*
G01X-1158700Y-16250D02*
X-1163369D01*
G01D02*
Y-10750D01*
G01Y-5450D02*
Y-5750D01*
X-1159700D01*
G01X-1125000Y-101700D02*
Y-110079D01*
G01X-1121850D02*
Y-104350D01*
X-1121870Y-104330D01*
G01X-1115551Y-110079D02*
Y-104301D01*
X-1115490Y-104240D01*
G01X-1118701Y-101759D02*
Y-110079D01*
G01X-1112402D02*
Y-101600D01*
G01X-1109252Y-110079D02*
Y-104248D01*
X-1109300Y-104200D01*
G01X-1106102Y-102100D02*
Y-110079D01*
G01X-1102953Y-104200D02*
Y-110079D01*
G01X-1033843Y-128576D02*
X-1031667Y-126400D01*
X-1009450D01*
X-1002810Y-133040D01*
Y-163883D01*
X-998740Y-167953D01*
G01X-1017670Y-123250D02*
X-1017020Y-122600D01*
X-999117D01*
X-994208Y-127509D01*
Y-169729D01*
X-990866Y-173071D01*
G01X-1022140Y-122960D02*
X-1020050Y-125050D01*
X-998541D01*
X-997421Y-126170D01*
X-997415D01*
X-995540Y-128044D01*
Y-128051D01*
X-995440Y-128151D01*
Y-174220D01*
X-991077Y-178583D01*
X-990866D01*
G01X-948500Y-175559D02*
X-963459D01*
X-970700Y-182800D01*
X-991200D01*
X-995500Y-178500D01*
Y-176705D01*
X-998740Y-173465D01*
G01X-927500Y-560000D02*
Y-600000D01*
G01X-915000Y-440000D02*
Y-480000D01*
G01X-890000D02*
Y-600000D01*
G01X-870000Y-440000D02*
Y-480000D01*
G01X-680000D02*
Y-440000D01*
G01X-594114Y-84390D02*
X-596614Y-81890D01*
G01X-460271Y-6000D02*
X-448700D01*
X-448600Y-5900D01*
G01X-452700Y-69000D02*
X-449141D01*
X-449100Y-68959D01*
G01X-432118Y-87082D02*
Y-87647D01*
X-436771Y-92300D01*
Y-92400D01*
G01X-433841Y-74100D02*
Y-79600D01*
G01Y-68600D02*
Y-74100D01*
G01X-429900Y-79600D02*
X-433841D01*
G01X-438959Y-68600D02*
X-441959D01*
G01X-429000Y-57600D02*
X-433841D01*
G01X-430700Y-63100D02*
X-433841D01*
G01X-430180Y-52100D02*
X-433841D01*
G01X-438959Y-46600D02*
X-442800D01*
G01X-433841Y-41100D02*
X-429400D01*
G01X-433841Y-35600D02*
Y-29500D01*
G01X-430400Y-35600D02*
X-433841D01*
G01X-429471Y-6900D02*
X-426300D01*
X-424500Y-8700D01*
Y-14300D01*
X-424600Y-14400D01*
G01X-380512Y-172598D02*
Y-180109D01*
X-379521Y-181100D01*
G01X-378937Y-162756D02*
Y-151563D01*
X-382900Y-147600D01*
Y-130740D01*
X-389600Y-124040D01*
Y-123640D01*
G01X-382087Y-162756D02*
Y-150413D01*
X-383910Y-148590D01*
Y-139993D01*
X-389770Y-134133D01*
Y-127220D01*
G01X-372638Y-162756D02*
Y-152962D01*
X-377200Y-148400D01*
X-379021D01*
X-380421Y-147000D01*
G01X-333450Y-174950D02*
Y-178400D01*
X-340210Y-185160D01*
X-348660D01*
X-354270Y-190770D01*
X-368510D01*
X-370400Y-188880D01*
Y-183530D01*
X-372830Y-181100D01*
X-379521D01*
G01X-377362Y-172598D02*
Y-177395D01*
X-377900Y-177933D01*
G01X-367913Y-179850D02*
Y-172598D01*
G01X-369488Y-162756D02*
Y-152867D01*
X-366421Y-149800D01*
Y-142079D01*
X-373620Y-134880D01*
Y-124430D01*
G01X-312100Y-113500D02*
X-312200D01*
X-314800Y-110900D01*
X-322800D01*
X-324500Y-112600D01*
Y-115800D01*
X-323100Y-117200D01*
Y-141300D01*
X-319055Y-145345D01*
Y-145512D01*
G01X-321600Y-113500D02*
Y-127500D01*
X-315000Y-134100D01*
Y-142087D01*
X-311181Y-145906D01*
G01X-318059Y-42000D02*
X-321700D01*
G01X-318059Y-47500D02*
X-321500D01*
G01X-317859Y-7300D02*
X-321800D01*
G01X-316500Y-113500D02*
X-307300Y-122700D01*
Y-137800D01*
X-309894Y-140394D01*
X-311181D01*
G01X-299259Y-43300D02*
X-303200D01*
G01X-299259Y-48800D02*
X-303200D01*
G01X-312941Y-47500D02*
X-309600D01*
X-309400Y-47700D01*
G01X-312869Y-19750D02*
Y-24950D01*
G01X-309400Y-25100D02*
X-312720D01*
X-312869Y-24950D01*
G01X-312741Y-30900D02*
Y-36400D01*
G01X-308500D02*
X-312741D01*
G01X-302500Y-15200D02*
X-302450Y-15250D01*
X-299131D01*
G01X-307900Y-13628D02*
X-312791D01*
G01X-312741Y-7300D02*
Y-1500D01*
G01Y-7300D02*
X-308900D01*
X-308800Y-7400D01*
G01X-294141Y-38000D02*
Y-32500D01*
G01D02*
X-289500D01*
G01X-293869Y-20750D02*
Y-25950D01*
G01X-290800Y-26000D02*
X-290850Y-25950D01*
X-293869D01*
G01X-299131Y-9750D02*
Y-15250D01*
G01X-293869Y-4450D02*
X-290350D01*
X-290300Y-4400D01*
G01X-254921Y-101700D02*
Y-110079D01*
G01X-245472D02*
Y-104301D01*
X-245411Y-104240D01*
G01X-248622Y-101759D02*
Y-110079D01*
G01X-251772D02*
Y-104350D01*
X-251792Y-104330D01*
G01X-242323Y-110079D02*
Y-101600D01*
G01X-239173Y-110079D02*
Y-104248D01*
X-239222Y-104200D01*
G01X-236024Y-102100D02*
Y-110079D01*
G01X-232874Y-104200D02*
Y-110079D01*
G01X-163764Y-128576D02*
X-151276D01*
X-148850Y-126150D01*
X-139621D01*
X-132731Y-133040D01*
Y-163883D01*
X-128661Y-167953D01*
G01X-150900Y-121100D02*
X-148750Y-123250D01*
X-128388D01*
X-124129Y-127509D01*
Y-169729D01*
X-120787Y-173071D01*
G01X-152400Y-125050D02*
X-151950Y-124600D01*
X-128912D01*
X-127342Y-126170D01*
X-127336D01*
X-125461Y-128044D01*
Y-128051D01*
X-125361Y-128151D01*
Y-174009D01*
X-120787Y-178583D01*
G01X-78400Y-176559D02*
X-98030D01*
X-101000Y-179529D01*
Y-181350D01*
X-102400Y-182750D01*
X-122100D01*
X-125421Y-179429D01*
Y-176750D01*
X-125453Y-176673D01*
X-128661Y-173465D01*
G01X-1200000Y-600000D02*
X-575000D01*
Y-440000D01*
X-1200000D01*
Y-600000D01*
G54D24*
X-1356889Y-145000D03*
X-1051613D03*
X-486810D03*
X-181534D03*
G54D33*
X-1120276Y-142362D03*
X-1123425D03*
X-1126575D03*
X-1128150Y-110079D03*
X-1125000D03*
X-1121850D03*
X-1104528Y-142362D03*
X-1107677D03*
X-1110827D03*
X-1113976D03*
X-1117126D03*
X-1118701Y-110079D03*
X-1115551D03*
X-1112402D03*
X-1109252D03*
X-1106102D03*
X-1098228Y-142362D03*
X-1101378D03*
X-1102953Y-110079D03*
X-1099803D03*
X-256496Y-142362D03*
X-258071Y-110079D03*
X-254921D03*
X-240748Y-142362D03*
X-243898D03*
X-247047D03*
X-250197D03*
X-253346D03*
X-251772Y-110079D03*
X-248622D03*
X-245472D03*
X-242323D03*
X-239173D03*
X-228150Y-142362D03*
X-231299D03*
X-234449D03*
X-237598D03*
X-236024Y-110079D03*
X-232874D03*
X-229724D03*
G54D15*
X-1654488Y7244D03*
X-1649488D03*
X-1644488D03*
X-1639488D03*
X-1634488D03*
X-1629488D03*
G54D43*
G01X-1489193Y-84390D02*
X-1491093Y-86290D01*
X-1496755D01*
X-1520545Y-62500D01*
X-1577244D01*
X-1604800Y-90056D01*
Y-174178D01*
X-1605454Y-174833D01*
X-1605954D01*
X-1608110Y-172677D01*
G01X-1489193Y-89390D02*
X-1491093Y-87490D01*
X-1497252D01*
X-1521042Y-63700D01*
X-1576747D01*
X-1603600Y-90553D01*
Y-174676D01*
X-1604957Y-176033D01*
X-1605954D01*
X-1608110Y-178189D01*
G01X-1600236Y-167559D02*
X-1598080Y-169715D01*
X-1597621D01*
X-1596874Y-168968D01*
Y-90520D01*
X-1573654Y-67300D01*
X-1524271D01*
X-1500806Y-90765D01*
Y-93917D01*
X-1498433Y-96290D01*
X-1496093D01*
X-1494193Y-94390D01*
G01X-1600236Y-173071D02*
X-1598080Y-170915D01*
X-1597124D01*
X-1595674Y-169465D01*
Y-91017D01*
X-1573157Y-68500D01*
X-1524768D01*
X-1502006Y-91262D01*
Y-94414D01*
X-1498930Y-97490D01*
X-1496093D01*
X-1494193Y-99390D01*
G01X-1489193Y-104390D02*
X-1491093Y-106290D01*
X-1499767D01*
X-1506544Y-99513D01*
Y-93087D01*
X-1507247Y-92384D01*
X-1527531Y-72100D01*
X-1569028D01*
X-1589000Y-92072D01*
Y-174127D01*
X-1589706Y-174833D01*
X-1590206D01*
X-1592362Y-172677D01*
G01X-1494193Y-114390D02*
X-1496093Y-116290D01*
X-1497910D01*
X-1511530Y-102670D01*
Y-95955D01*
X-1530585Y-76900D01*
X-1565495D01*
X-1581158Y-92563D01*
Y-169041D01*
X-1581832Y-169715D01*
X-1582332D01*
X-1584488Y-167559D01*
G01X-1489193Y-109390D02*
X-1491093Y-107490D01*
X-1500265D01*
X-1507744Y-100010D01*
Y-93584D01*
X-1528028Y-73300D01*
X-1568531D01*
X-1587800Y-92569D01*
Y-174624D01*
X-1589209Y-176033D01*
X-1590206D01*
X-1592362Y-178189D01*
G01X-1494193Y-119390D02*
X-1496093Y-117490D01*
X-1498407D01*
X-1512730Y-103167D01*
Y-96452D01*
X-1531082Y-78100D01*
X-1564998D01*
X-1579958Y-93060D01*
Y-169538D01*
X-1581335Y-170915D01*
X-1582332D01*
X-1584488Y-173071D01*
G01X-1489193Y-124390D02*
X-1491093Y-126290D01*
X-1498710D01*
X-1516300Y-108700D01*
X-1516303D01*
X-1522300Y-102703D01*
Y-93176D01*
X-1533776Y-81700D01*
X-1561553D01*
X-1573300Y-93447D01*
Y-174175D01*
X-1573958Y-174833D01*
X-1574458D01*
X-1576614Y-172677D01*
G01X-1494193Y-134390D02*
X-1496003Y-136200D01*
X-1497303D01*
X-1501400Y-132103D01*
Y-130600D01*
X-1517000Y-115000D01*
X-1517003D01*
X-1528000Y-104003D01*
Y-94264D01*
X-1535764Y-86500D01*
X-1556860D01*
X-1565400Y-95040D01*
Y-169031D01*
X-1566084Y-169715D01*
X-1566584D01*
X-1568740Y-167559D01*
G01X-1489193Y-129390D02*
X-1491093Y-127490D01*
X-1499207D01*
X-1516797Y-109900D01*
X-1516800D01*
X-1523500Y-103200D01*
Y-93673D01*
X-1534273Y-82900D01*
X-1561056D01*
X-1572100Y-93944D01*
Y-174672D01*
X-1573461Y-176033D01*
X-1574458D01*
X-1576614Y-178189D01*
G01X-1494193Y-139390D02*
X-1496183Y-137400D01*
X-1497800D01*
X-1502600Y-132600D01*
Y-131097D01*
X-1517497Y-116200D01*
X-1517500D01*
X-1529200Y-104500D01*
Y-94761D01*
X-1536261Y-87700D01*
X-1556363D01*
X-1564200Y-95537D01*
Y-169528D01*
X-1565587Y-170915D01*
X-1566584D01*
X-1568740Y-173071D01*
G01X-1489193Y-144390D02*
X-1491093Y-146290D01*
X-1498634D01*
X-1501148Y-143776D01*
Y-140702D01*
X-1512350Y-129500D01*
X-1526803D01*
X-1533500Y-122803D01*
Y-95552D01*
X-1537643Y-91409D01*
X-1551125D01*
X-1551128Y-91406D01*
X-1554856D01*
X-1557492Y-94041D01*
Y-94304D01*
X-1557500Y-94311D01*
Y-174123D01*
X-1558210Y-174833D01*
X-1558710D01*
X-1560866Y-172677D01*
G01X-1494193Y-154390D02*
X-1496093Y-156290D01*
X-1500013D01*
X-1501500Y-154803D01*
Y-150212D01*
X-1504800Y-146912D01*
Y-144427D01*
X-1514427Y-134800D01*
X-1528500D01*
X-1538752Y-124548D01*
Y-99127D01*
X-1541484Y-96395D01*
X-1547084D01*
X-1549619Y-98930D01*
Y-168998D01*
X-1550336Y-169715D01*
X-1550836D01*
X-1552992Y-167559D01*
G01X-1489193Y-149390D02*
X-1491093Y-147490D01*
X-1499131D01*
X-1502348Y-144273D01*
Y-141199D01*
X-1512847Y-130700D01*
X-1527300D01*
X-1534700Y-123300D01*
Y-96050D01*
X-1538141Y-92609D01*
X-1551622D01*
X-1551625Y-92606D01*
X-1554359D01*
X-1556292Y-94538D01*
Y-94801D01*
X-1556300Y-94809D01*
Y-174620D01*
X-1557713Y-176033D01*
X-1558710D01*
X-1560866Y-178189D01*
G01X-1494193Y-159390D02*
X-1496093Y-157490D01*
X-1500510D01*
X-1502700Y-155300D01*
Y-150709D01*
X-1506000Y-147409D01*
Y-144924D01*
X-1514924Y-136000D01*
X-1528997D01*
X-1539952Y-125045D01*
Y-99624D01*
X-1541981Y-97595D01*
X-1546587D01*
X-1548419Y-99427D01*
Y-169495D01*
X-1549839Y-170915D01*
X-1550836D01*
X-1552992Y-173071D01*
G01X-1545118Y-172677D02*
X-1542962Y-174833D01*
X-1508525D01*
X-1499982Y-166290D01*
X-1491093D01*
X-1489193Y-164390D01*
G01X-1545118Y-178189D02*
X-1542962Y-176033D01*
X-1508028D01*
X-1499485Y-167490D01*
X-1491093D01*
X-1489193Y-169390D01*
G01X-1484193Y-154390D02*
X-1486693Y-151890D01*
G01X-1484193Y-159390D02*
X-1486693Y-156890D01*
G01X-1484193Y-134390D02*
X-1486693Y-131890D01*
G01X-1484193Y-139390D02*
X-1486693Y-136890D01*
G01X-1484193Y-119390D02*
X-1486693Y-116890D01*
G01X-1484193Y-114390D02*
X-1486693Y-111890D01*
G01X-1484193Y-94390D02*
X-1486693Y-91890D01*
G01X-1484193Y-99390D02*
X-1486693Y-96890D01*
G01X-1469193Y-169390D02*
X-1471693Y-166890D01*
G01X-1479193Y-169390D02*
X-1481693Y-166890D01*
G01X-1474193Y-154390D02*
X-1476693Y-151890D01*
G01X-1469193Y-164390D02*
X-1471693Y-161890D01*
G01X-1469193Y-149390D02*
X-1471693Y-146890D01*
G01X-1474193Y-159390D02*
X-1476693Y-156890D01*
G01X-1479193Y-164390D02*
X-1481693Y-161890D01*
G01X-1479193Y-149390D02*
X-1481693Y-146890D01*
G01X-1474193Y-134390D02*
X-1476693Y-131890D01*
G01X-1469193Y-144390D02*
X-1471693Y-141890D01*
G01X-1474193Y-139390D02*
X-1476693Y-136890D01*
G01X-1479193Y-144390D02*
X-1481693Y-141890D01*
G01X-1469193Y-124390D02*
X-1471693Y-121890D01*
G01X-1474193Y-119390D02*
X-1476693Y-116890D01*
G01X-1469193Y-129390D02*
X-1471693Y-126890D01*
G01X-1479193Y-124390D02*
X-1481693Y-121890D01*
G01X-1479193Y-129390D02*
X-1481693Y-126890D01*
G01X-1469193Y-104390D02*
X-1471693Y-101890D01*
G01X-1474193Y-114390D02*
X-1476693Y-111890D01*
G01X-1469193Y-109390D02*
X-1471693Y-106890D01*
G01X-1479193Y-104390D02*
X-1481693Y-101890D01*
G01X-1479193Y-109390D02*
X-1481693Y-106890D01*
G01Y-86890D02*
Y-86895D01*
X-1479198Y-89390D01*
X-1479193D01*
G01X-1471693Y-86890D02*
X-1471590D01*
X-1469193Y-89287D01*
Y-89390D01*
G01X-1474193Y-94390D02*
X-1476693Y-91890D01*
G01X-1474193Y-99390D02*
X-1476693Y-96890D01*
G01X-1481693Y-81890D02*
X-1481679D01*
X-1479193Y-84376D01*
Y-84390D01*
G01X-1471693Y-81890D02*
X-1469193Y-84390D01*
G01X-1474193Y-74390D02*
X-1476693Y-71890D01*
G01X-1479193Y-74390D02*
X-1481693Y-71890D01*
G01X-1469193Y-74390D02*
X-1471693Y-71890D01*
G01X-1474193Y-79390D02*
X-1476693Y-76890D01*
G01X-1479193Y-79390D02*
X-1481693Y-76890D01*
G01X-1469193Y-79390D02*
X-1471693Y-76890D01*
G01X-1459193Y-169390D02*
X-1461693Y-166890D01*
G01X-1464193Y-154390D02*
X-1466693Y-151890D01*
G01X-1459193Y-164390D02*
X-1461693Y-161890D01*
G01X-1459193Y-149390D02*
X-1461693Y-146890D01*
G01X-1464193Y-159390D02*
X-1466693Y-156890D01*
G01X-1464193Y-134390D02*
X-1466693Y-131890D01*
G01X-1459193Y-144390D02*
X-1461693Y-141890D01*
G01X-1464193Y-139390D02*
X-1466693Y-136890D01*
G01X-1459193Y-124390D02*
X-1461693Y-121890D01*
G01X-1464193Y-119390D02*
X-1466693Y-116890D01*
G01X-1459193Y-129390D02*
X-1461693Y-126890D01*
G01X-1464193Y-114390D02*
X-1466693Y-111890D01*
G01X-1459193Y-104390D02*
X-1461693Y-101890D01*
G01X-1459193Y-109390D02*
X-1461693Y-106890D01*
G01X-1459193Y-89390D02*
Y-89384D01*
X-1461687Y-86890D01*
X-1461693D01*
G01X-1464193Y-94390D02*
X-1466693Y-91890D01*
G01X-1464193Y-99390D02*
X-1466693Y-96890D01*
G01X-1461693Y-81890D02*
Y-81967D01*
X-1459270Y-84390D01*
X-1459193D01*
G01Y-74390D02*
X-1461693Y-71890D01*
G01X-1464193Y-79390D02*
X-1466693Y-76890D01*
G01X-1464193Y-84390D02*
X-1466693Y-81890D01*
G01X-1459193Y-79390D02*
X-1461693Y-76890D01*
G01X-1464193Y-74390D02*
X-1466693Y-71890D01*
G01X-1007500Y-470000D02*
X-1006450Y-475000D01*
X-1005250Y-470000D01*
X-1004050Y-475000D01*
X-1003000Y-470000D01*
G01X-1001125Y-475000D02*
X-999250Y-470000D01*
X-997375Y-475000D01*
G01X-998050Y-473250D02*
X-1000450D01*
G01X-994825Y-474333D02*
X-994225Y-474750D01*
X-993550Y-475000D01*
X-992950D01*
X-992350Y-474750D01*
X-991900Y-474333D01*
X-991675Y-473750D01*
X-991825Y-473167D01*
X-992200Y-472667D01*
X-992875Y-472333D01*
X-993775Y-472167D01*
X-994300Y-471833D01*
X-994525Y-471250D01*
X-994375Y-470667D01*
X-994000Y-470250D01*
X-993475Y-470000D01*
X-992950D01*
X-992425Y-470167D01*
X-991975Y-470583D01*
G01X-988825Y-475000D02*
Y-470000D01*
G01X-985675D02*
Y-475000D01*
G01Y-472500D02*
X-988825D01*
G01X-976525Y-474417D02*
X-976000Y-474833D01*
X-975400Y-475000D01*
X-974800Y-474833D01*
X-974275Y-474333D01*
X-973900Y-473583D01*
X-973750Y-472833D01*
Y-471917D01*
X-973900Y-471167D01*
X-974275Y-470500D01*
X-974725Y-470167D01*
X-975250Y-470000D01*
X-975850Y-470167D01*
X-976300Y-470500D01*
X-976600Y-471000D01*
X-976750Y-471667D01*
X-976600Y-472250D01*
X-976225Y-472833D01*
X-975775Y-473167D01*
X-975250Y-473250D01*
X-974650Y-473083D01*
X-974200Y-472667D01*
X-973750Y-471917D01*
G01X-969250Y-475000D02*
X-968725Y-474917D01*
X-968125Y-474667D01*
X-967750Y-474250D01*
X-967600Y-473667D01*
X-967750Y-473083D01*
X-968200Y-472583D01*
X-968875Y-472333D01*
X-969625D01*
X-970075Y-472167D01*
X-970450Y-471750D01*
X-970600Y-471167D01*
X-970375Y-470583D01*
X-969850Y-470167D01*
X-969250Y-470000D01*
X-968650Y-470167D01*
X-968125Y-470583D01*
X-967900Y-471167D01*
X-968050Y-471750D01*
X-968425Y-472167D01*
X-968875Y-472333D01*
X-969625D01*
X-970300Y-472583D01*
X-970750Y-473083D01*
X-970900Y-473667D01*
X-970750Y-474250D01*
X-970375Y-474667D01*
X-969775Y-474917D01*
X-969250Y-475000D01*
G01X-963250Y-470000D02*
X-963850Y-470167D01*
X-964300Y-470583D01*
X-964600Y-471083D01*
X-964825Y-471750D01*
X-964900Y-472500D01*
X-964825Y-473250D01*
X-964600Y-473917D01*
X-964300Y-474417D01*
X-963850Y-474833D01*
X-963250Y-475000D01*
X-962650Y-474833D01*
X-962200Y-474417D01*
X-961900Y-473917D01*
X-961675Y-473250D01*
X-961600Y-472500D01*
X-961675Y-471750D01*
X-961900Y-471083D01*
X-962200Y-470583D01*
X-962650Y-470167D01*
X-963250Y-470000D01*
G01X-958900Y-474250D02*
X-958450Y-474667D01*
X-957925Y-474917D01*
X-957250Y-475000D01*
X-956575Y-474833D01*
X-956050Y-474500D01*
X-955675Y-473917D01*
X-955600Y-473250D01*
X-955750Y-472583D01*
X-956125Y-472167D01*
X-956650Y-471833D01*
X-957175Y-471750D01*
X-957700Y-471833D01*
X-958375Y-472167D01*
X-958150Y-470000D01*
X-956125D01*
G01X-952675Y-470833D02*
X-952225Y-470333D01*
X-951700Y-470083D01*
X-951100Y-470000D01*
X-950350Y-470167D01*
X-949825Y-470583D01*
X-949675Y-471083D01*
X-949750Y-471583D01*
X-950050Y-472000D01*
X-951550Y-472833D01*
X-952225Y-473417D01*
X-952675Y-474250D01*
X-952825Y-475000D01*
X-949675D01*
G01X-946225Y-473333D02*
X-944275D01*
G01X-940675Y-472917D02*
X-940150Y-472333D01*
X-939700Y-472000D01*
X-939100Y-471833D01*
X-938575Y-472000D01*
X-938200Y-472333D01*
X-937900Y-472833D01*
X-937825Y-473417D01*
X-937900Y-473917D01*
X-938200Y-474417D01*
X-938650Y-474833D01*
X-939175Y-475000D01*
X-939775Y-474833D01*
X-940300Y-474333D01*
X-940600Y-473583D01*
X-940675Y-472750D01*
X-940525Y-471667D01*
X-940300Y-471083D01*
X-939925Y-470500D01*
X-939400Y-470083D01*
X-938875Y-470000D01*
X-938350Y-470167D01*
X-937975Y-470583D01*
G01X-934900Y-474000D02*
X-934450Y-474583D01*
X-933850Y-474917D01*
X-933175Y-475000D01*
X-932575Y-474917D01*
X-931975Y-474500D01*
X-931600Y-474000D01*
X-931525Y-473500D01*
X-931675Y-472917D01*
X-932200Y-472500D01*
X-932725Y-472333D01*
X-933400D01*
G01X-932725D02*
X-932275Y-472083D01*
X-931900Y-471667D01*
X-931750Y-471167D01*
X-931900Y-470667D01*
X-932275Y-470250D01*
X-932950Y-470000D01*
X-933625Y-470083D01*
X-934300Y-470417D01*
G01X-928525Y-474417D02*
X-928000Y-474833D01*
X-927400Y-475000D01*
X-926800Y-474833D01*
X-926275Y-474333D01*
X-925900Y-473583D01*
X-925750Y-472833D01*
Y-471917D01*
X-925900Y-471167D01*
X-926275Y-470500D01*
X-926725Y-470167D01*
X-927250Y-470000D01*
X-927850Y-470167D01*
X-928300Y-470500D01*
X-928600Y-471000D01*
X-928750Y-471667D01*
X-928600Y-472250D01*
X-928225Y-472833D01*
X-927775Y-473167D01*
X-927250Y-473250D01*
X-926650Y-473083D01*
X-926200Y-472667D01*
X-925750Y-471917D01*
G01X-922525Y-474417D02*
X-922000Y-474833D01*
X-921400Y-475000D01*
X-920800Y-474833D01*
X-920275Y-474333D01*
X-919900Y-473583D01*
X-919750Y-472833D01*
Y-471917D01*
X-919900Y-471167D01*
X-920275Y-470500D01*
X-920725Y-470167D01*
X-921250Y-470000D01*
X-921850Y-470167D01*
X-922300Y-470500D01*
X-922600Y-471000D01*
X-922750Y-471667D01*
X-922600Y-472250D01*
X-922225Y-472833D01*
X-921775Y-473167D01*
X-921250Y-473250D01*
X-920650Y-473083D01*
X-920200Y-472667D01*
X-919750Y-471917D01*
G01X-1006750Y-465000D02*
Y-460000D01*
X-1004875D01*
X-1004275Y-460250D01*
X-1003900Y-460583D01*
X-1003750Y-461250D01*
X-1003900Y-461917D01*
X-1004350Y-462333D01*
X-1004875Y-462583D01*
X-1006750D01*
G01X-1004875D02*
X-1003750Y-465000D01*
G01X-997750D02*
X-1000750D01*
Y-460000D01*
X-997750D01*
G01X-998950Y-462417D02*
X-1000750D01*
G01X-994900Y-465000D02*
Y-460000D01*
X-993400D01*
X-992800Y-460250D01*
X-992350Y-460583D01*
X-991975Y-461083D01*
X-991675Y-461667D01*
X-991600Y-462500D01*
X-991675Y-463333D01*
X-991975Y-463917D01*
X-992350Y-464417D01*
X-992800Y-464750D01*
X-993400Y-465000D01*
X-994900D01*
G01X-989200D02*
Y-460000D01*
X-987250Y-464167D01*
X-985300Y-460000D01*
Y-465000D01*
G01X-981250D02*
X-981850Y-464917D01*
X-982375Y-464583D01*
X-982825Y-464083D01*
X-983125Y-463500D01*
X-983275Y-462833D01*
Y-462167D01*
X-983125Y-461500D01*
X-982825Y-460917D01*
X-982375Y-460417D01*
X-981850Y-460083D01*
X-981250Y-460000D01*
X-980650Y-460083D01*
X-980125Y-460417D01*
X-979675Y-460917D01*
X-979375Y-461500D01*
X-979225Y-462167D01*
Y-462833D01*
X-979375Y-463500D01*
X-979675Y-464083D01*
X-980125Y-464583D01*
X-980650Y-464917D01*
X-981250Y-465000D01*
G01X-976975D02*
Y-460000D01*
X-973525Y-465000D01*
Y-460000D01*
G01X-970900Y-465000D02*
Y-460000D01*
X-969400D01*
X-968800Y-460250D01*
X-968350Y-460583D01*
X-967975Y-461083D01*
X-967675Y-461667D01*
X-967600Y-462500D01*
X-967675Y-463333D01*
X-967975Y-463917D01*
X-968350Y-464417D01*
X-968800Y-464750D01*
X-969400Y-465000D01*
X-970900D01*
G01X-1005250Y-455000D02*
Y-450000D01*
X-1006150Y-451000D01*
G01Y-455000D02*
X-1004350D01*
G01X-995200D02*
Y-450000D01*
X-993250Y-454167D01*
X-991300Y-450000D01*
Y-455000D01*
G01X-988150Y-450000D02*
X-986350D01*
G01X-987250D02*
Y-455000D01*
G01X-988150D02*
X-986350D01*
G01X-979600Y-450417D02*
X-980050Y-450167D01*
X-980575Y-450000D01*
X-981175D01*
X-981850Y-450250D01*
X-982375Y-450667D01*
X-982750Y-451167D01*
X-983050Y-452000D01*
X-983125Y-452750D01*
X-982975Y-453500D01*
X-982750Y-454000D01*
X-982300Y-454500D01*
X-981775Y-454833D01*
X-981250Y-455000D01*
X-980725D01*
X-980200Y-454833D01*
X-979750Y-454583D01*
X-979375Y-454250D01*
G01X-976750Y-455000D02*
Y-450000D01*
X-974875D01*
X-974275Y-450250D01*
X-973900Y-450583D01*
X-973750Y-451250D01*
X-973900Y-451917D01*
X-974350Y-452333D01*
X-974875Y-452583D01*
X-976750D01*
G01X-974875D02*
X-973750Y-455000D01*
G01X-969250D02*
X-969850Y-454917D01*
X-970375Y-454583D01*
X-970825Y-454083D01*
X-971125Y-453500D01*
X-971275Y-452833D01*
Y-452167D01*
X-971125Y-451500D01*
X-970825Y-450917D01*
X-970375Y-450417D01*
X-969850Y-450083D01*
X-969250Y-450000D01*
X-968650Y-450083D01*
X-968125Y-450417D01*
X-967675Y-450917D01*
X-967375Y-451500D01*
X-967225Y-452167D01*
Y-452833D01*
X-967375Y-453500D01*
X-967675Y-454083D01*
X-968125Y-454583D01*
X-968650Y-454917D01*
X-969250Y-455000D01*
G01X-964825Y-454333D02*
X-964225Y-454750D01*
X-963550Y-455000D01*
X-962950D01*
X-962350Y-454750D01*
X-961900Y-454333D01*
X-961675Y-453750D01*
X-961825Y-453167D01*
X-962200Y-452667D01*
X-962875Y-452333D01*
X-963775Y-452167D01*
X-964300Y-451833D01*
X-964525Y-451250D01*
X-964375Y-450667D01*
X-964000Y-450250D01*
X-963475Y-450000D01*
X-962950D01*
X-962425Y-450167D01*
X-961975Y-450583D01*
G01X-957250Y-455000D02*
X-957850Y-454917D01*
X-958375Y-454583D01*
X-958825Y-454083D01*
X-959125Y-453500D01*
X-959275Y-452833D01*
Y-452167D01*
X-959125Y-451500D01*
X-958825Y-450917D01*
X-958375Y-450417D01*
X-957850Y-450083D01*
X-957250Y-450000D01*
X-956650Y-450083D01*
X-956125Y-450417D01*
X-955675Y-450917D01*
X-955375Y-451500D01*
X-955225Y-452167D01*
Y-452833D01*
X-955375Y-453500D01*
X-955675Y-454083D01*
X-956125Y-454583D01*
X-956650Y-454917D01*
X-957250Y-455000D01*
G01X-952675D02*
Y-450000D01*
X-949825D01*
G01X-950875Y-452417D02*
X-952675D01*
G01X-945250Y-450000D02*
Y-455000D01*
G01X-946975Y-450000D02*
X-943525D01*
G01X-935500D02*
X-934450Y-455000D01*
X-933250Y-450000D01*
X-932050Y-455000D01*
X-931000Y-450000D01*
G01X-929125Y-455000D02*
X-927250Y-450000D01*
X-925375Y-455000D01*
G01X-926050Y-453250D02*
X-928450D01*
G01X-921250Y-455000D02*
Y-452750D01*
X-922750Y-450000D01*
G01X-919750D02*
X-921250Y-452750D01*
G01X-619114Y-84390D02*
X-621014Y-86290D01*
X-626676D01*
X-651966Y-61000D01*
X-705665D01*
X-734721Y-90056D01*
Y-174178D01*
X-735376Y-174833D01*
X-735876D01*
X-738032Y-172677D01*
G01Y-178189D02*
X-735876Y-176033D01*
X-734879D01*
X-733521Y-174676D01*
Y-90553D01*
X-705168Y-62200D01*
X-652463D01*
X-627174Y-87490D01*
X-621014D01*
X-619114Y-89390D01*
G01X-730157Y-167559D02*
X-728002Y-169715D01*
X-727542D01*
X-726795Y-168968D01*
Y-92695D01*
X-700375Y-66275D01*
X-655217D01*
X-630727Y-90765D01*
Y-93917D01*
X-628354Y-96290D01*
X-626014D01*
X-624114Y-94390D01*
G01X-730157Y-173071D02*
X-728002Y-170915D01*
X-727045D01*
X-725595Y-169465D01*
Y-93192D01*
X-699878Y-67475D01*
X-655714D01*
X-631927Y-91262D01*
Y-94414D01*
X-628852Y-97490D01*
X-626014D01*
X-624114Y-99390D01*
G01X-722283Y-172677D02*
X-720128Y-174833D01*
X-719628D01*
X-718921Y-174127D01*
Y-92072D01*
X-698315Y-71466D01*
X-658086D01*
X-637168Y-92384D01*
X-636465Y-93087D01*
Y-99513D01*
X-629689Y-106290D01*
X-621014D01*
X-619114Y-104390D01*
G01X-624114Y-114390D02*
X-626014Y-116290D01*
X-626713D01*
X-641451Y-101552D01*
Y-95955D01*
X-660818Y-76588D01*
X-695104D01*
X-711080Y-92563D01*
Y-169041D01*
X-711754Y-169715D01*
X-712254D01*
X-714409Y-167559D01*
G01X-722283Y-178189D02*
X-720128Y-176033D01*
X-719130D01*
X-717721Y-174624D01*
Y-92569D01*
X-697818Y-72666D01*
X-658583D01*
X-637665Y-93584D01*
Y-100010D01*
X-630186Y-107490D01*
X-621014D01*
X-619114Y-109390D01*
G01X-714409Y-173071D02*
X-712254Y-170915D01*
X-711256D01*
X-709880Y-169538D01*
Y-93060D01*
X-694607Y-77788D01*
X-661315D01*
X-642651Y-96452D01*
Y-102049D01*
X-627210Y-117490D01*
X-626014D01*
X-624114Y-119390D01*
G01X-619114Y-124390D02*
X-621014Y-126290D01*
X-630786D01*
X-632800Y-124276D01*
Y-118303D01*
X-652300Y-98803D01*
Y-93097D01*
X-663960Y-81437D01*
X-691211D01*
X-703221Y-93447D01*
Y-174175D01*
X-703880Y-174833D01*
X-704380D01*
X-706535Y-172677D01*
G01X-698661Y-167559D02*
X-696506Y-169715D01*
X-696006D01*
X-695321Y-169031D01*
Y-95040D01*
X-686568Y-86287D01*
X-665898D01*
X-657800Y-94385D01*
Y-100300D01*
X-638400Y-119700D01*
Y-126582D01*
X-628692Y-136290D01*
X-626014D01*
X-624114Y-134390D01*
G01X-619114Y-129390D02*
X-621014Y-127490D01*
X-631284D01*
X-634000Y-124773D01*
Y-118800D01*
X-653500Y-99300D01*
Y-93594D01*
X-664457Y-82637D01*
X-690714D01*
X-702021Y-93944D01*
Y-174672D01*
X-703382Y-176033D01*
X-704380D01*
X-706535Y-178189D01*
G01X-624114Y-139390D02*
X-626014Y-137490D01*
X-629190D01*
X-639600Y-127079D01*
Y-120197D01*
X-659000Y-100797D01*
Y-94883D01*
X-666396Y-87487D01*
X-686071D01*
X-694121Y-95537D01*
Y-169528D01*
X-695508Y-170915D01*
X-696506D01*
X-698661Y-173071D01*
G01X-690787Y-172677D02*
X-688631Y-174833D01*
X-688131D01*
X-687421Y-174123D01*
Y-94311D01*
X-687413Y-94304D01*
Y-94041D01*
X-684778Y-91406D01*
X-681049D01*
X-681046Y-91409D01*
X-667565D01*
X-663500Y-95474D01*
Y-108271D01*
X-663500Y-119500D01*
X-653600Y-129400D01*
X-642371D01*
X-630000Y-141771D01*
Y-141803D01*
X-625513Y-146290D01*
X-621014D01*
X-619114Y-144390D01*
G01X-624114Y-154390D02*
X-626014Y-156290D01*
X-628613D01*
X-632200Y-152703D01*
Y-146948D01*
X-644948Y-134200D01*
X-656070D01*
X-668673Y-121597D01*
Y-99127D01*
X-671405Y-96395D01*
X-677005D01*
X-679540Y-98930D01*
Y-168998D01*
X-680257Y-169715D01*
X-680757D01*
X-682913Y-167559D01*
G01X-690787Y-178189D02*
X-688632Y-176033D01*
X-687634D01*
X-686221Y-174620D01*
Y-94809D01*
X-686213Y-94801D01*
Y-94538D01*
X-684280Y-92606D01*
X-681546D01*
X-681543Y-92609D01*
X-668062D01*
X-664700Y-95971D01*
Y-107774D01*
X-664700Y-119997D01*
X-654097Y-130600D01*
X-642868D01*
X-631200Y-142268D01*
Y-142300D01*
X-626010Y-147490D01*
X-621014D01*
X-619114Y-149390D01*
G01X-624114Y-159390D02*
X-626014Y-157490D01*
X-629110D01*
X-633400Y-153200D01*
Y-147445D01*
X-645445Y-135400D01*
X-656567D01*
X-669873Y-122094D01*
Y-99624D01*
X-671902Y-97595D01*
X-676508D01*
X-678340Y-99427D01*
Y-169495D01*
X-679760Y-170915D01*
X-680757D01*
X-682913Y-173071D01*
G01X-675039Y-172677D02*
X-672883Y-174833D01*
X-638446D01*
X-629903Y-166290D01*
X-621014D01*
X-619114Y-164390D01*
G01X-675039Y-178189D02*
X-672883Y-176033D01*
X-637949D01*
X-629406Y-167490D01*
X-621014D01*
X-619114Y-169390D01*
G01X-649700Y-120241D02*
Y-117200D01*
G01X-614114Y-154390D02*
X-616614Y-151890D01*
G01X-614114Y-159390D02*
X-616614Y-156890D01*
G01X-614114Y-139390D02*
X-616614Y-136890D01*
G01X-614114Y-134390D02*
X-616614Y-131890D01*
G01X-614114Y-114390D02*
X-616614Y-111890D01*
G01X-614114Y-119390D02*
X-616614Y-116890D01*
G01X-614114Y-94390D02*
X-616614Y-91890D01*
G01X-614114Y-99390D02*
X-616614Y-96890D01*
G01X-599114Y-169390D02*
X-601614Y-166890D01*
G01X-609114Y-169390D02*
X-611614Y-166890D01*
G01X-604114Y-154390D02*
X-606614Y-151890D01*
G01X-599114Y-164390D02*
X-601614Y-161890D01*
G01X-604114Y-159390D02*
X-606614Y-156890D01*
G01X-609114Y-164390D02*
X-611614Y-161890D01*
G01X-609114Y-149390D02*
X-611614Y-146890D01*
G01X-604114Y-134390D02*
X-606614Y-131890D01*
G01X-599114Y-144390D02*
X-601614Y-141890D01*
G01X-604114Y-139390D02*
X-606614Y-136890D01*
G01X-599114Y-149390D02*
X-601614Y-146890D01*
G01X-609114Y-144390D02*
X-611614Y-141890D01*
G01X-599114Y-124390D02*
X-601614Y-121890D01*
G01X-604114Y-119390D02*
X-606614Y-116890D01*
G01X-599114Y-129390D02*
X-601614Y-126890D01*
G01X-609114Y-124390D02*
X-611614Y-121890D01*
G01X-609114Y-129390D02*
X-611614Y-126890D01*
G01X-599114Y-104390D02*
X-601614Y-101890D01*
G01X-604114Y-114390D02*
X-606614Y-111890D01*
G01X-599114Y-109390D02*
X-601614Y-106890D01*
G01X-609114Y-104390D02*
X-611614Y-101890D01*
G01X-609114Y-109390D02*
X-611614Y-106890D01*
G01Y-86890D02*
X-609114Y-89390D01*
G01X-601614Y-86890D02*
X-599114Y-89390D01*
G01X-604114Y-94390D02*
X-606614Y-91890D01*
G01X-604114Y-99390D02*
X-606614Y-96890D01*
G01X-611614Y-81890D02*
X-609114Y-84390D01*
G01X-601614Y-81890D02*
X-599114Y-84390D01*
G01X-604114Y-74390D02*
X-606614Y-71890D01*
G01X-609114Y-74390D02*
X-611614Y-71890D01*
G01X-599114Y-74390D02*
X-601614Y-71890D01*
G01X-604114Y-79390D02*
X-606614Y-76890D01*
G01X-609114Y-79390D02*
X-611614Y-76890D01*
G01X-599114Y-79390D02*
X-601614Y-76890D01*
G01X-589114Y-169390D02*
X-591614Y-166890D01*
G01X-594114Y-154390D02*
X-596614Y-151890D01*
G01X-589114Y-164390D02*
X-591614Y-161890D01*
G01X-589114Y-149390D02*
X-591614Y-146890D01*
G01X-594114Y-159390D02*
X-596614Y-156890D01*
G01X-594114Y-134390D02*
X-596614Y-131890D01*
G01X-589114Y-144390D02*
X-591614Y-141890D01*
G01X-594114Y-139390D02*
X-596614Y-136890D01*
G01X-589114Y-124390D02*
X-591614Y-121890D01*
G01X-594114Y-119390D02*
X-596614Y-116890D01*
G01X-589114Y-129390D02*
X-591614Y-126890D01*
G01X-594114Y-114390D02*
X-596614Y-111890D01*
G01X-589114Y-104390D02*
X-591614Y-101890D01*
G01X-589114Y-109390D02*
X-591614Y-106890D01*
G01X-589114Y-89390D02*
X-591614Y-86890D01*
G01X-594114Y-94390D02*
X-596614Y-91890D01*
G01X-594114Y-99390D02*
X-596614Y-96890D01*
G01X-589114Y-84390D02*
X-591614Y-81890D01*
G01X-589114Y-74390D02*
X-591614Y-71890D01*
G01X-594114Y-79390D02*
X-596614Y-76890D01*
G01X-589114Y-79390D02*
X-591614Y-76890D01*
G01X-594114Y-74390D02*
X-596614Y-71890D01*
G54D34*
X-1025000Y-50942D03*
Y1459D03*
X-1015157Y-105312D03*
X-997441D03*
X-981693Y-50942D03*
Y1459D03*
X-971850Y-105312D03*
X-954134D03*
X-938386Y-50942D03*
Y1459D03*
X-145079Y-105312D03*
X-154921Y-50942D03*
Y1459D03*
X-127362Y-105312D03*
X-111614Y-50942D03*
Y1459D03*
X-101772Y-105312D03*
X-84055D03*
X-68307Y-50942D03*
Y1459D03*
G54D16*
X-1615984Y-173071D03*
Y-178583D03*
Y-167559D03*
X-1608110Y-172677D03*
Y-178189D03*
Y-167165D03*
X-1615984Y-162047D03*
Y-151024D03*
Y-156535D03*
X-1608110Y-161654D03*
Y-150630D03*
Y-156142D03*
X-1615984Y-134488D03*
Y-140000D03*
Y-145512D03*
X-1608110Y-134094D03*
Y-139606D03*
Y-145118D03*
X-1615984Y-128976D03*
Y-123465D03*
Y-117953D03*
X-1608110Y-128583D03*
Y-123071D03*
Y-117559D03*
X-1615984Y-112441D03*
Y-106929D03*
Y-101417D03*
X-1608110Y-112047D03*
Y-106535D03*
Y-101024D03*
X-1615984Y-95906D03*
X-1600236Y-167559D03*
X-1592362Y-167165D03*
X-1600236Y-173071D03*
X-1592362Y-172677D03*
X-1600236Y-178583D03*
X-1592362Y-178189D03*
X-1600236Y-151024D03*
X-1592362Y-150630D03*
X-1600236Y-156535D03*
X-1592362Y-156142D03*
X-1600236Y-162047D03*
X-1592362Y-161654D03*
X-1600236Y-134488D03*
X-1592362Y-134094D03*
X-1600236Y-140000D03*
X-1592362Y-139606D03*
X-1600236Y-145512D03*
X-1592362Y-145118D03*
X-1600236Y-128976D03*
Y-117953D03*
Y-123465D03*
X-1592362Y-128583D03*
Y-117559D03*
Y-123071D03*
X-1600236Y-101417D03*
Y-106929D03*
Y-112441D03*
X-1592362Y-101024D03*
Y-106535D03*
Y-112047D03*
X-1600236Y-95906D03*
X-1584488Y-167559D03*
X-1576614Y-167165D03*
X-1584488Y-173071D03*
X-1576614Y-172677D03*
X-1584488Y-178583D03*
X-1576614Y-178189D03*
X-1584488Y-151024D03*
X-1576614Y-150630D03*
X-1584488Y-156535D03*
X-1576614Y-156142D03*
X-1584488Y-162047D03*
X-1576614Y-161654D03*
X-1584488Y-134488D03*
X-1576614Y-134094D03*
X-1584488Y-140000D03*
X-1576614Y-139606D03*
X-1584488Y-145512D03*
X-1576614Y-145118D03*
X-1584488Y-128976D03*
X-1576614Y-128583D03*
X-1584488Y-117953D03*
X-1576614Y-117559D03*
X-1584488Y-123465D03*
X-1576614Y-123071D03*
X-1584488Y-101417D03*
X-1576614Y-101024D03*
X-1584488Y-106929D03*
X-1576614Y-106535D03*
X-1584488Y-112441D03*
X-1576614Y-112047D03*
X-1584488Y-95906D03*
X-1568740Y-167559D03*
X-1560866Y-167165D03*
X-1568740Y-173071D03*
X-1560866Y-172677D03*
X-1568740Y-178583D03*
X-1560866Y-178189D03*
X-1568740Y-151024D03*
X-1560866Y-150630D03*
X-1568740Y-156535D03*
X-1560866Y-156142D03*
X-1568740Y-162047D03*
X-1560866Y-161654D03*
X-1568740Y-134488D03*
X-1560866Y-134094D03*
X-1568740Y-140000D03*
X-1560866Y-139606D03*
X-1568740Y-145512D03*
X-1560866Y-145118D03*
X-1568740Y-128976D03*
Y-117953D03*
Y-123465D03*
X-1560866Y-128583D03*
Y-117559D03*
Y-123071D03*
X-1568740Y-101417D03*
Y-106929D03*
Y-112441D03*
X-1560866Y-101024D03*
Y-106535D03*
Y-112047D03*
X-1568740Y-95906D03*
X-1552992Y-167559D03*
X-1545118Y-167165D03*
X-1552992Y-173071D03*
X-1545118Y-172677D03*
X-1552992Y-178583D03*
Y-151024D03*
X-1545118Y-150630D03*
X-1552992Y-156535D03*
X-1545118Y-156142D03*
X-1552992Y-162047D03*
X-1545118Y-161654D03*
X-1552992Y-134488D03*
X-1545118Y-134094D03*
X-1552992Y-140000D03*
X-1545118Y-139606D03*
X-1552992Y-145512D03*
X-1545118Y-145118D03*
X-1552992Y-128976D03*
Y-117953D03*
Y-123465D03*
X-1545118Y-128583D03*
Y-117559D03*
Y-123071D03*
X-1552992Y-101417D03*
Y-106929D03*
Y-112441D03*
X-1545118Y-101024D03*
Y-106535D03*
Y-112047D03*
X-1552992Y-95906D03*
X-1197008Y-167953D03*
X-1189134Y-167559D03*
X-1197008Y-173465D03*
X-1189134Y-173071D03*
X-1197008Y-178976D03*
X-1189134Y-178583D03*
X-1197008Y-151417D03*
X-1189134Y-151024D03*
X-1197008Y-156929D03*
X-1189134Y-156535D03*
X-1197008Y-162441D03*
X-1189134Y-162047D03*
X-1197008Y-134882D03*
X-1189134Y-134488D03*
X-1197008Y-140394D03*
X-1189134Y-140000D03*
X-1197008Y-145906D03*
X-1189134Y-145512D03*
X-1197008Y-129370D03*
X-1181260Y-167953D03*
X-1173386Y-167559D03*
X-1181260Y-173465D03*
X-1173386Y-173071D03*
X-1181260Y-178976D03*
X-1173386Y-178583D03*
X-1181260Y-151417D03*
X-1173386Y-151024D03*
X-1181260Y-156929D03*
X-1173386Y-156535D03*
X-1181260Y-162441D03*
X-1173386Y-162047D03*
X-1181260Y-134882D03*
X-1173386Y-134488D03*
X-1181260Y-140394D03*
X-1173386Y-140000D03*
X-1181260Y-145906D03*
X-1173386Y-145512D03*
X-1181260Y-129370D03*
X-1165512Y-167953D03*
X-1157638Y-167559D03*
X-1165512Y-173465D03*
X-1157638Y-173071D03*
X-1165512Y-178976D03*
X-1157638Y-178583D03*
X-1165512Y-151417D03*
X-1157638Y-151024D03*
X-1165512Y-156929D03*
X-1157638Y-156535D03*
X-1165512Y-162441D03*
X-1157638Y-162047D03*
X-1165512Y-134882D03*
X-1157638Y-134488D03*
X-1165512Y-140394D03*
X-1157638Y-140000D03*
X-1165512Y-145906D03*
X-1157638Y-145512D03*
X-1165512Y-129370D03*
X-1014488Y-167953D03*
Y-173465D03*
Y-178976D03*
Y-151417D03*
Y-156929D03*
Y-162441D03*
Y-134882D03*
Y-140394D03*
Y-145906D03*
Y-129370D03*
X-1006614Y-167559D03*
X-998740Y-167953D03*
X-1006614Y-173071D03*
X-998740Y-173465D03*
X-1006614Y-178583D03*
X-998740Y-178976D03*
X-1006614Y-151024D03*
X-998740Y-151417D03*
X-1006614Y-156535D03*
X-998740Y-156929D03*
X-1006614Y-162047D03*
X-998740Y-162441D03*
X-1006614Y-134488D03*
X-998740Y-134882D03*
X-1006614Y-140000D03*
X-998740Y-140394D03*
X-1006614Y-145512D03*
X-998740Y-145906D03*
Y-129370D03*
X-990866Y-167559D03*
X-982992Y-167953D03*
X-990866Y-173071D03*
X-982992Y-173465D03*
X-990866Y-178583D03*
X-982992Y-178976D03*
X-990866Y-151024D03*
X-982992Y-151417D03*
X-990866Y-156535D03*
X-982992Y-156929D03*
X-990866Y-162047D03*
X-982992Y-162441D03*
X-990866Y-134488D03*
X-982992Y-134882D03*
X-990866Y-140000D03*
X-982992Y-140394D03*
X-990866Y-145512D03*
X-982992Y-145906D03*
Y-129370D03*
X-975118Y-167559D03*
Y-173071D03*
Y-178583D03*
Y-151024D03*
Y-156535D03*
Y-162047D03*
Y-134488D03*
Y-140000D03*
Y-145512D03*
X-745906Y-173071D03*
Y-178583D03*
Y-167559D03*
Y-162047D03*
Y-151024D03*
Y-156535D03*
Y-134488D03*
Y-140000D03*
Y-145512D03*
Y-128976D03*
Y-123465D03*
Y-117953D03*
Y-112441D03*
Y-106929D03*
Y-101417D03*
Y-95906D03*
X-738032Y-172677D03*
Y-178189D03*
Y-167165D03*
X-730157Y-167559D03*
Y-173071D03*
Y-178583D03*
X-738032Y-161654D03*
Y-150630D03*
Y-156142D03*
X-730157Y-151024D03*
Y-156535D03*
Y-162047D03*
X-738032Y-134094D03*
Y-139606D03*
Y-145118D03*
X-730157Y-134488D03*
Y-140000D03*
Y-145512D03*
Y-128976D03*
X-738032Y-128583D03*
X-730157Y-117953D03*
Y-123465D03*
X-738032Y-123071D03*
Y-117559D03*
X-730157Y-101417D03*
Y-106929D03*
Y-112441D03*
X-738032Y-112047D03*
Y-106535D03*
Y-101024D03*
X-730157Y-95906D03*
X-722283Y-167165D03*
X-714409Y-167559D03*
X-722283Y-172677D03*
X-714409Y-173071D03*
X-722283Y-178189D03*
X-714409Y-178583D03*
X-722283Y-150630D03*
X-714409Y-151024D03*
X-722283Y-156142D03*
X-714409Y-156535D03*
X-722283Y-161654D03*
X-714409Y-162047D03*
X-722283Y-134094D03*
X-714409Y-134488D03*
X-722283Y-139606D03*
X-714409Y-140000D03*
X-722283Y-145118D03*
X-714409Y-145512D03*
X-722283Y-128583D03*
Y-117559D03*
Y-123071D03*
X-714409Y-128976D03*
Y-117953D03*
Y-123465D03*
X-722283Y-101024D03*
Y-106535D03*
Y-112047D03*
X-714409Y-101417D03*
Y-106929D03*
Y-112441D03*
Y-95906D03*
X-706535Y-167165D03*
X-698661Y-167559D03*
X-706535Y-172677D03*
X-698661Y-173071D03*
X-706535Y-178189D03*
X-698661Y-178583D03*
X-706535Y-150630D03*
X-698661Y-151024D03*
X-706535Y-156142D03*
X-698661Y-156535D03*
X-706535Y-161654D03*
X-698661Y-162047D03*
X-706535Y-134094D03*
X-698661Y-134488D03*
X-706535Y-139606D03*
X-698661Y-140000D03*
X-706535Y-145118D03*
X-698661Y-145512D03*
X-706535Y-128583D03*
Y-117559D03*
Y-123071D03*
X-698661Y-128976D03*
Y-117953D03*
Y-123465D03*
X-706535Y-101024D03*
Y-106535D03*
Y-112047D03*
X-698661Y-101417D03*
Y-106929D03*
Y-112441D03*
Y-95906D03*
X-690787Y-167165D03*
X-682913Y-167559D03*
X-690787Y-172677D03*
X-682913Y-173071D03*
X-690787Y-178189D03*
X-682913Y-178583D03*
X-690787Y-150630D03*
X-682913Y-151024D03*
X-690787Y-156142D03*
X-682913Y-156535D03*
X-690787Y-161654D03*
X-682913Y-162047D03*
X-690787Y-134094D03*
X-682913Y-134488D03*
X-690787Y-139606D03*
X-682913Y-140000D03*
X-690787Y-145118D03*
X-682913Y-145512D03*
X-690787Y-128583D03*
X-682913Y-128976D03*
X-690787Y-117559D03*
X-682913Y-117953D03*
X-690787Y-123071D03*
X-682913Y-123465D03*
X-690787Y-101024D03*
X-682913Y-101417D03*
X-690787Y-106535D03*
X-682913Y-106929D03*
X-690787Y-112047D03*
X-682913Y-112441D03*
Y-95906D03*
X-675039Y-167165D03*
Y-172677D03*
Y-150630D03*
Y-156142D03*
Y-161654D03*
Y-134094D03*
Y-139606D03*
Y-145118D03*
Y-128583D03*
Y-117559D03*
Y-123071D03*
Y-101024D03*
Y-106535D03*
Y-112047D03*
X-326929Y-167953D03*
X-319055Y-167559D03*
X-326929Y-173465D03*
X-319055Y-173071D03*
X-326929Y-178976D03*
X-319055Y-178583D03*
X-326929Y-151417D03*
X-319055Y-151024D03*
X-326929Y-156929D03*
X-319055Y-156535D03*
X-326929Y-162441D03*
X-319055Y-162047D03*
X-326929Y-134882D03*
X-319055Y-134488D03*
X-326929Y-140394D03*
X-319055Y-140000D03*
X-326929Y-145906D03*
X-319055Y-145512D03*
X-326929Y-129370D03*
X-311181Y-167953D03*
X-303307Y-167559D03*
X-311181Y-173465D03*
X-303307Y-173071D03*
X-311181Y-178976D03*
X-303307Y-178583D03*
X-311181Y-151417D03*
X-303307Y-151024D03*
X-311181Y-156929D03*
X-303307Y-156535D03*
X-311181Y-162441D03*
X-303307Y-162047D03*
X-311181Y-134882D03*
X-303307Y-134488D03*
X-311181Y-140394D03*
X-303307Y-140000D03*
X-311181Y-145906D03*
X-303307Y-145512D03*
X-311181Y-129370D03*
X-295433Y-167953D03*
X-287559Y-167559D03*
X-295433Y-173465D03*
X-287559Y-173071D03*
X-295433Y-178976D03*
X-287559Y-178583D03*
X-295433Y-151417D03*
X-287559Y-151024D03*
X-295433Y-156929D03*
X-287559Y-156535D03*
X-295433Y-162441D03*
X-287559Y-162047D03*
X-295433Y-134882D03*
X-287559Y-134488D03*
X-295433Y-140394D03*
X-287559Y-140000D03*
X-295433Y-145906D03*
X-287559Y-145512D03*
X-295433Y-129370D03*
X-144409Y-167953D03*
Y-173465D03*
Y-178976D03*
Y-151417D03*
Y-156929D03*
Y-162441D03*
Y-134882D03*
Y-140394D03*
Y-145906D03*
Y-129370D03*
X-136535Y-167559D03*
X-128661Y-167953D03*
X-136535Y-173071D03*
X-128661Y-173465D03*
X-136535Y-178583D03*
X-128661Y-178976D03*
X-136535Y-151024D03*
X-128661Y-151417D03*
X-136535Y-156535D03*
X-128661Y-156929D03*
X-136535Y-162047D03*
X-128661Y-162441D03*
X-136535Y-134488D03*
X-128661Y-134882D03*
X-136535Y-140000D03*
X-128661Y-140394D03*
X-136535Y-145512D03*
X-128661Y-145906D03*
Y-129370D03*
X-120787Y-167559D03*
X-112913Y-167953D03*
X-120787Y-173071D03*
X-112913Y-173465D03*
X-120787Y-178583D03*
X-112913Y-178976D03*
X-120787Y-151024D03*
X-112913Y-151417D03*
X-120787Y-156535D03*
X-112913Y-156929D03*
X-120787Y-162047D03*
X-112913Y-162441D03*
X-120787Y-134488D03*
X-112913Y-134882D03*
X-120787Y-140000D03*
X-112913Y-140394D03*
X-120787Y-145512D03*
X-112913Y-145906D03*
Y-129370D03*
X-105039Y-167559D03*
Y-173071D03*
Y-178583D03*
Y-151024D03*
Y-156535D03*
Y-162047D03*
Y-134488D03*
Y-140000D03*
Y-145512D03*
G54D25*
X-1341850Y-16000D03*
X-1330350Y-6000D03*
X-1311050Y-16900D03*
X-1299550Y-6900D03*
X-471771Y-16000D03*
X-460271Y-6000D03*
X-440971Y-16900D03*
X-429471Y-6900D03*
G54D44*
G01X-874510Y-499000D02*
Y-493000D01*
X-871290Y-499000D01*
Y-493000D01*
G01X-867200Y-499000D02*
X-867760Y-498900D01*
X-868250Y-498500D01*
X-868670Y-497900D01*
X-868950Y-497200D01*
X-869090Y-496400D01*
Y-495600D01*
X-868950Y-494800D01*
X-868670Y-494100D01*
X-868250Y-493500D01*
X-867760Y-493100D01*
X-867200Y-493000D01*
X-866640Y-493100D01*
X-866150Y-493500D01*
X-865730Y-494100D01*
X-865450Y-494800D01*
X-865310Y-495600D01*
Y-496400D01*
X-865450Y-497200D01*
X-865730Y-497900D01*
X-866150Y-498500D01*
X-866640Y-498900D01*
X-867200Y-499000D01*
G01X-861500Y-493000D02*
Y-499000D01*
G01X-863110Y-493000D02*
X-859890D01*
G01X-856640D02*
X-854960D01*
G01X-855800D02*
Y-499000D01*
G01X-856640D02*
X-854960D01*
G01X-848560Y-493500D02*
X-848980Y-493200D01*
X-849470Y-493000D01*
X-850030D01*
X-850660Y-493300D01*
X-851150Y-493800D01*
X-851500Y-494400D01*
X-851780Y-495400D01*
X-851850Y-496300D01*
X-851710Y-497200D01*
X-851500Y-497800D01*
X-851080Y-498400D01*
X-850590Y-498800D01*
X-850100Y-499000D01*
X-849610D01*
X-849120Y-498800D01*
X-848700Y-498500D01*
X-848350Y-498100D01*
G01X-843000Y-499000D02*
X-845800D01*
Y-493000D01*
X-843000D01*
G01X-844120Y-495900D02*
X-845800D01*
G01X-833000Y-499000D02*
X-833560Y-498900D01*
X-834050Y-498500D01*
X-834470Y-497900D01*
X-834750Y-497200D01*
X-834890Y-496400D01*
Y-495600D01*
X-834750Y-494800D01*
X-834470Y-494100D01*
X-834050Y-493500D01*
X-833560Y-493100D01*
X-833000Y-493000D01*
X-832440Y-493100D01*
X-831950Y-493500D01*
X-831530Y-494100D01*
X-831250Y-494800D01*
X-831110Y-495600D01*
Y-496400D01*
X-831250Y-497200D01*
X-831530Y-497900D01*
X-831950Y-498500D01*
X-832440Y-498900D01*
X-833000Y-499000D01*
G01X-828630D02*
Y-493000D01*
X-825970D01*
G01X-826950Y-495900D02*
X-828630D01*
G01X-817300Y-499000D02*
Y-493000D01*
X-815620D01*
X-815060Y-493300D01*
X-814640Y-494000D01*
X-814500Y-494800D01*
X-814640Y-495600D01*
X-814990Y-496200D01*
X-815620Y-496500D01*
X-817300D01*
G01X-811600Y-499000D02*
Y-493000D01*
X-809850D01*
X-809290Y-493300D01*
X-808940Y-493700D01*
X-808800Y-494500D01*
X-808940Y-495300D01*
X-809360Y-495800D01*
X-809850Y-496100D01*
X-811600D01*
G01X-809850D02*
X-808800Y-499000D01*
G01X-804500D02*
X-805060Y-498900D01*
X-805550Y-498500D01*
X-805970Y-497900D01*
X-806250Y-497200D01*
X-806390Y-496400D01*
Y-495600D01*
X-806250Y-494800D01*
X-805970Y-494100D01*
X-805550Y-493500D01*
X-805060Y-493100D01*
X-804500Y-493000D01*
X-803940Y-493100D01*
X-803450Y-493500D01*
X-803030Y-494100D01*
X-802750Y-494800D01*
X-802610Y-495600D01*
Y-496400D01*
X-802750Y-497200D01*
X-803030Y-497900D01*
X-803450Y-498500D01*
X-803940Y-498900D01*
X-804500Y-499000D01*
G01X-800200D02*
Y-493000D01*
X-798520D01*
X-797960Y-493300D01*
X-797540Y-494000D01*
X-797400Y-494800D01*
X-797540Y-495600D01*
X-797890Y-496200D01*
X-798520Y-496500D01*
X-800200D01*
G01X-794500Y-499000D02*
Y-493000D01*
X-792750D01*
X-792190Y-493300D01*
X-791840Y-493700D01*
X-791700Y-494500D01*
X-791840Y-495300D01*
X-792260Y-495800D01*
X-792750Y-496100D01*
X-794500D01*
G01X-792750D02*
X-791700Y-499000D01*
G01X-788240Y-493000D02*
X-786560D01*
G01X-787400D02*
Y-499000D01*
G01X-788240D02*
X-786560D01*
G01X-780300D02*
X-783100D01*
Y-493000D01*
X-780300D01*
G01X-781420Y-495900D02*
X-783100D01*
G01X-776000Y-493000D02*
Y-499000D01*
G01X-777610Y-493000D02*
X-774390D01*
G01X-772050Y-499000D02*
X-770300Y-493000D01*
X-768550Y-499000D01*
G01X-769180Y-496900D02*
X-771420D01*
G01X-766000Y-499000D02*
Y-493000D01*
X-764250D01*
X-763690Y-493300D01*
X-763340Y-493700D01*
X-763200Y-494500D01*
X-763340Y-495300D01*
X-763760Y-495800D01*
X-764250Y-496100D01*
X-766000D01*
G01X-764250D02*
X-763200Y-499000D01*
G01X-758900D02*
Y-496300D01*
X-760300Y-493000D01*
G01X-757500D02*
X-758900Y-496300D01*
G01X-748900Y-499000D02*
Y-493000D01*
X-747220D01*
X-746660Y-493300D01*
X-746240Y-494000D01*
X-746100Y-494800D01*
X-746240Y-495600D01*
X-746590Y-496200D01*
X-747220Y-496500D01*
X-748900D01*
G01X-743200Y-499000D02*
Y-493000D01*
X-741450D01*
X-740890Y-493300D01*
X-740540Y-493700D01*
X-740400Y-494500D01*
X-740540Y-495300D01*
X-740960Y-495800D01*
X-741450Y-496100D01*
X-743200D01*
G01X-741450D02*
X-740400Y-499000D01*
G01X-736100D02*
X-736660Y-498900D01*
X-737150Y-498500D01*
X-737570Y-497900D01*
X-737850Y-497200D01*
X-737990Y-496400D01*
Y-495600D01*
X-737850Y-494800D01*
X-737570Y-494100D01*
X-737150Y-493500D01*
X-736660Y-493100D01*
X-736100Y-493000D01*
X-735540Y-493100D01*
X-735050Y-493500D01*
X-734630Y-494100D01*
X-734350Y-494800D01*
X-734210Y-495600D01*
Y-496400D01*
X-734350Y-497200D01*
X-734630Y-497900D01*
X-735050Y-498500D01*
X-735540Y-498900D01*
X-736100Y-499000D01*
G01X-731800D02*
Y-493000D01*
X-730120D01*
X-729560Y-493300D01*
X-729140Y-494000D01*
X-729000Y-494800D01*
X-729140Y-495600D01*
X-729490Y-496200D01*
X-730120Y-496500D01*
X-731800D01*
G01X-723300Y-499000D02*
X-726100D01*
Y-493000D01*
X-723300D01*
G01X-724420Y-495900D02*
X-726100D01*
G01X-720400Y-499000D02*
Y-493000D01*
X-718650D01*
X-718090Y-493300D01*
X-717740Y-493700D01*
X-717600Y-494500D01*
X-717740Y-495300D01*
X-718160Y-495800D01*
X-718650Y-496100D01*
X-720400D01*
G01X-718650D02*
X-717600Y-499000D01*
G01X-713300Y-493000D02*
Y-499000D01*
G01X-714910Y-493000D02*
X-711690D01*
G01X-707600Y-499000D02*
Y-496300D01*
X-709000Y-493000D01*
G01X-706200D02*
X-707600Y-496300D01*
G01X-701900Y-499200D02*
X-702040Y-499100D01*
Y-498900D01*
X-701900Y-498800D01*
X-701760Y-498900D01*
Y-499100D01*
X-701900Y-499200D01*
G01Y-496500D02*
X-702040Y-496400D01*
Y-496200D01*
X-701900Y-496100D01*
X-701760Y-496200D01*
Y-496400D01*
X-701900Y-496500D01*
G54D17*
X-1600709Y4685D03*
X-1560709D03*
X-1520709D03*
X-1480709D03*
G54D26*
X-1327756Y-127795D03*
X-457677D03*
G54D35*
X-1015157Y-95824D03*
X-1012205Y-93068D03*
X-1009252Y-98580D03*
X-1015157Y-80864D03*
X-1012205Y-78108D03*
X-1009252Y-83620D03*
X-1015157Y-65903D03*
X-1012205Y-63147D03*
X-1009252Y-68659D03*
X-1015157Y-50942D03*
X-1012205Y-48187D03*
X-1009252Y-53698D03*
X-1006299Y-95824D03*
X-1000394Y-98580D03*
X-1003346Y-93068D03*
X-997441Y-95824D03*
X-994488Y-93068D03*
X-1000394Y-83620D03*
X-1006299Y-80864D03*
X-1003346Y-78108D03*
X-997441Y-80864D03*
X-994488Y-78108D03*
X-1006299Y-65903D03*
X-1003346Y-63147D03*
X-1000394Y-68659D03*
X-997441Y-65903D03*
X-994488Y-63147D03*
X-1006299Y-50942D03*
X-1003346Y-48187D03*
X-1000394Y-53698D03*
X-997441Y-50942D03*
X-994488Y-48187D03*
X-991535Y-98580D03*
Y-83620D03*
Y-68659D03*
Y-53698D03*
X-971850Y-95824D03*
X-968898Y-93068D03*
X-965945Y-98580D03*
X-962992Y-95824D03*
X-971850Y-80864D03*
X-965945Y-83620D03*
X-962992Y-80864D03*
X-968898Y-78108D03*
X-971850Y-65903D03*
X-965945Y-68659D03*
X-962992Y-65903D03*
X-968898Y-63147D03*
X-971850Y-50942D03*
X-965945Y-53698D03*
X-962992Y-50942D03*
X-968898Y-48187D03*
X-960039Y-93068D03*
X-957087Y-98580D03*
X-954134Y-95824D03*
X-951181Y-93068D03*
X-948228Y-98580D03*
X-960039Y-78108D03*
X-948228Y-83620D03*
X-957087D03*
X-954134Y-80864D03*
X-951181Y-78108D03*
X-960039Y-63147D03*
X-948228Y-68659D03*
X-957087D03*
X-954134Y-65903D03*
X-951181Y-63147D03*
X-960039Y-48187D03*
X-948228Y-53698D03*
X-957087D03*
X-954134Y-50942D03*
X-951181Y-48187D03*
X-145079Y-95824D03*
Y-80864D03*
Y-65903D03*
Y-50942D03*
X-142126Y-93068D03*
X-139173Y-98580D03*
X-136220Y-95824D03*
X-130315Y-98580D03*
X-133268Y-93068D03*
X-127362Y-95824D03*
X-142126Y-78108D03*
X-139173Y-83620D03*
X-130315D03*
X-136220Y-80864D03*
X-133268Y-78108D03*
X-127362Y-80864D03*
X-142126Y-63147D03*
X-139173Y-68659D03*
X-136220Y-65903D03*
X-133268Y-63147D03*
X-130315Y-68659D03*
X-127362Y-65903D03*
X-142126Y-48187D03*
X-139173Y-53698D03*
X-136220Y-50942D03*
X-133268Y-48187D03*
X-130315Y-53698D03*
X-127362Y-50942D03*
X-121457Y-98580D03*
X-124409Y-93068D03*
X-121457Y-83620D03*
X-124409Y-78108D03*
X-121457Y-68659D03*
X-124409Y-63147D03*
X-121457Y-53698D03*
X-124409Y-48187D03*
X-101772Y-95824D03*
X-98819Y-93068D03*
X-95866Y-98580D03*
X-101772Y-80864D03*
X-95866Y-83620D03*
X-98819Y-78108D03*
X-101772Y-65903D03*
X-95866Y-68659D03*
X-98819Y-63147D03*
X-101772Y-50942D03*
X-95866Y-53698D03*
X-98819Y-48187D03*
X-92913Y-95824D03*
X-89961Y-93068D03*
X-87008Y-98580D03*
X-84055Y-95824D03*
X-81102Y-93068D03*
X-92913Y-80864D03*
X-89961Y-78108D03*
X-87008Y-83620D03*
X-84055Y-80864D03*
X-81102Y-78108D03*
X-92913Y-65903D03*
X-89961Y-63147D03*
X-87008Y-68659D03*
X-84055Y-65903D03*
X-81102Y-63147D03*
X-92913Y-50942D03*
X-89961Y-48187D03*
X-87008Y-53698D03*
X-84055Y-50942D03*
X-81102Y-48187D03*
X-78150Y-98580D03*
Y-83620D03*
Y-68659D03*
Y-53698D03*
G54D45*
G01X-1269488Y-172598D02*
Y-176461D01*
G03X-1269365Y-176758I420J0D01*
G01X-1268891Y-177232D01*
G02X-1268768Y-177529I-297J-297D01*
G01Y-182892D01*
X-1269513Y-183637D01*
G01X-1266339Y-172598D02*
Y-176461D01*
G02X-1266462Y-176758I-420J0D01*
G01X-1266935Y-177232D01*
G03X-1267058Y-177529I297J-297D01*
G01Y-182892D01*
X-1266313Y-183637D01*
G01X-1271063Y-162756D02*
Y-158893D01*
G02X-1270940Y-158596I420J0D01*
G01X-1270466Y-158122D01*
G03X-1270343Y-157825I-297J297D01*
G01Y-153579D01*
G03X-1271088Y-151780I-2544J0D01*
G01X-1267913Y-162756D02*
Y-158893D01*
G03X-1268036Y-158596I-420J0D01*
G01X-1268510Y-158122D01*
G02X-1268633Y-157825I297J297D01*
G01Y-153579D01*
G02X-1267888Y-151780I2544J0D01*
G01X-1260039Y-172598D02*
Y-176635D01*
X-1259320Y-177355D01*
Y-187810D01*
G03X-1256250Y-190880I3070J0D01*
G01X-1253716D01*
G03X-1250551Y-189569I0J4476D01*
G01X-1250511Y-189529D01*
G02X-1249620Y-189160I891J-891D01*
G01X-1247509D01*
G02X-1245710Y-189905I0J-2544D01*
G01X-1256890Y-172598D02*
Y-176635D01*
X-1257610Y-177355D01*
Y-178175D01*
X-1256850Y-178935D01*
Y-180790D01*
X-1257610Y-181550D01*
Y-187810D01*
G03X-1256250Y-189170I1360J0D01*
G01X-1253716D01*
G03X-1251760Y-188360I0J2766D01*
G01X-1251720Y-188320D01*
G02X-1249620Y-187450I2100J-2100D01*
G01X-1247509D01*
G03X-1245710Y-186705I0J2544D01*
G01X-1261614Y-162756D02*
Y-158893D01*
G02X-1261491Y-158596I420J0D01*
G01X-1261017Y-158122D01*
G03X-1260894Y-157825I-297J297D01*
G01Y-146200D01*
G03X-1261625Y-144435I-2496J0D01*
G01X-1258465Y-162756D02*
Y-158893D01*
G03X-1258588Y-158596I-420J0D01*
G01X-1259061Y-158122D01*
G02X-1259184Y-157825I297J297D01*
G01Y-146268D01*
G02X-1258425Y-144435I2591J0D01*
G01X-1228543Y-172598D02*
Y-176635D01*
X-1229263Y-177355D01*
Y-178801D01*
X-1232901Y-182439D01*
G03X-1233100Y-182920I481J-481D01*
G01Y-183545D01*
G03X-1232340Y-185380I2595J0D01*
G01X-1231693Y-172598D02*
Y-176635D01*
X-1230973Y-177355D01*
Y-178093D01*
X-1233240Y-180360D01*
X-1234110Y-181230D01*
G03X-1234810Y-182920I1690J-1690D01*
G01Y-183618D01*
G02X-1235540Y-185380I-2492J0D01*
G01X-1230118Y-162756D02*
Y-158893D01*
G03X-1230241Y-158596I-420J0D01*
G01X-1230715Y-158122D01*
G02X-1230838Y-157825I297J297D01*
G01Y-136149D01*
G02X-1230093Y-134350I2544J0D01*
G01X-1233268Y-162756D02*
Y-158893D01*
G02X-1233145Y-158596I420J0D01*
G01X-1232671Y-158122D01*
G03X-1232548Y-157825I-297J297D01*
G01Y-136149D01*
G03X-1233293Y-134350I-2544J0D01*
G01X-1222244Y-172598D02*
Y-176461D01*
G03X-1222121Y-176758I420J0D01*
G01X-1221647Y-177232D01*
G02X-1221524Y-177529I-297J-297D01*
G01Y-179680D01*
G03X-1218994Y-182210I2530J0D01*
G01X-1214620D01*
G03X-1206880Y-174470I0J7740D01*
G01Y-168953D01*
G02X-1206220Y-167360I2253J0D01*
G01X-1219094Y-172598D02*
Y-176461D01*
G02X-1219218Y-176758I-420J0D01*
G01X-1219691Y-177232D01*
G03X-1219814Y-177529I297J-297D01*
G01Y-179680D01*
G03X-1218994Y-180500I820J0D01*
G01X-1218174D01*
X-1217494Y-179820D01*
X-1216274D01*
X-1215594Y-180500D01*
X-1214620D01*
G03X-1208590Y-174470I0J6030D01*
G01Y-174010D01*
X-1209740Y-172860D01*
Y-171334D01*
X-1208590Y-170184D01*
Y-169364D01*
G03X-1209420Y-167360I-2834J0D01*
G01X-1220669Y-162756D02*
Y-158893D01*
G03X-1220792Y-158596I-420J0D01*
G01X-1221266Y-158122D01*
G02X-1221389Y-157825I297J297D01*
G01Y-151829D01*
G02X-1220590Y-149900I2729J0D01*
G01X-1223819Y-162756D02*
Y-158893D01*
G02X-1223696Y-158596I420J0D01*
G01X-1223222Y-158122D01*
G03X-1223099Y-157825I-297J297D01*
G01Y-151568D01*
G03X-1223790Y-149900I-2359J0D01*
G01X-1123425Y-142362D02*
Y-147465D01*
X-1122705Y-148185D01*
Y-153384D01*
G02X-1123450Y-155183I-2544J0D01*
G01X-1120276Y-142362D02*
Y-147416D01*
X-1120995Y-148135D01*
Y-153384D01*
G03X-1120250Y-155183I2544J0D01*
G01X-1101378Y-142362D02*
Y-137362D01*
X-1102100Y-136640D01*
Y-122070D01*
G03X-1104970Y-119200I-2870J0D01*
G01X-1106905D01*
G02X-1108703Y-118455I0J2544D01*
G01X-1104528Y-142362D02*
Y-137328D01*
X-1103810Y-136610D01*
Y-122070D01*
G03X-1104970Y-120910I-1160J0D01*
G01X-1106905D01*
G03X-1108703Y-121655I0J-2544D01*
G01X-399409Y-172598D02*
Y-176461D01*
G03X-399286Y-176758I420J0D01*
G01X-398813Y-177232D01*
G02X-398690Y-177529I-297J-297D01*
G01Y-182892D01*
X-399435Y-183637D01*
G01X-396260Y-172598D02*
Y-176461D01*
G02X-396383Y-176758I-420J0D01*
G01X-396857Y-177232D01*
G03X-396980Y-177529I297J-297D01*
G01Y-182892D01*
X-396235Y-183637D01*
G01X-400984Y-162756D02*
Y-158893D01*
G02X-400861Y-158596I420J0D01*
G01X-400387Y-158122D01*
G03X-400264Y-157825I-297J297D01*
G01Y-153579D01*
G03X-401009Y-151780I-2544J0D01*
G01X-397835Y-162756D02*
Y-158893D01*
G03X-397958Y-158596I-420J0D01*
G01X-398431Y-158122D01*
G02X-398554Y-157825I297J297D01*
G01Y-153579D01*
G02X-397809Y-151780I2544J0D01*
G01X-389961Y-172598D02*
Y-176635D01*
X-389241Y-177355D01*
Y-187810D01*
G03X-386171Y-190880I3070J0D01*
G01X-383637D01*
G03X-380472Y-189569I0J4476D01*
G01X-380432Y-189529D01*
G02X-379541Y-189160I891J-891D01*
G01X-377430D01*
G02X-375631Y-189905I0J-2544D01*
G01X-386811Y-172598D02*
Y-176635D01*
X-387531Y-177355D01*
Y-178175D01*
X-386771Y-178935D01*
Y-180790D01*
X-387531Y-181550D01*
Y-187810D01*
G03X-386171Y-189170I1360J0D01*
G01X-383637D01*
G03X-381681Y-188360I0J2766D01*
G01X-381641Y-188320D01*
G02X-379541Y-187450I2100J-2100D01*
G01X-377430D01*
G03X-375631Y-186705I0J2544D01*
G01X-391535Y-162756D02*
Y-158893D01*
G02X-391412Y-158596I420J0D01*
G01X-390939Y-158122D01*
G03X-390816Y-157825I-297J297D01*
G01Y-146200D01*
G03X-391547Y-144435I-2496J0D01*
G01X-388386Y-162756D02*
Y-158893D01*
G03X-388509Y-158596I-420J0D01*
G01X-388983Y-158122D01*
G02X-389106Y-157825I297J297D01*
G01Y-146268D01*
G02X-388347Y-144435I2591J0D01*
G01X-361614Y-172598D02*
Y-176635D01*
X-360894Y-177355D01*
Y-178093D01*
X-363161Y-180360D01*
X-364031Y-181230D01*
G03X-364731Y-182920I1690J-1690D01*
G01Y-183618D01*
G02X-365461Y-185380I-2492J0D01*
G01X-352165Y-172598D02*
Y-176461D01*
G03X-352042Y-176758I420J0D01*
G01X-351569Y-177232D01*
G02X-351446Y-177529I-297J-297D01*
G01Y-179680D01*
G03X-348916Y-182210I2530J0D01*
G01X-344541D01*
G03X-336801Y-174470I0J7740D01*
G01Y-168953D01*
G02X-336141Y-167360I2253J0D01*
G01X-358465Y-172598D02*
Y-176635D01*
X-359184Y-177355D01*
Y-178801D01*
X-362822Y-182439D01*
G03X-363021Y-182920I481J-481D01*
G01Y-183545D01*
G03X-362261Y-185380I2595J0D01*
G01X-349016Y-172598D02*
Y-176461D01*
G02X-349139Y-176758I-420J0D01*
G01X-349613Y-177232D01*
G03X-349736Y-177529I297J-297D01*
G01Y-179680D01*
G03X-348916Y-180500I820J0D01*
G01X-348096D01*
X-347416Y-179820D01*
X-346196D01*
X-345516Y-180500D01*
X-344541D01*
G03X-338511Y-174470I0J6030D01*
G01Y-174010D01*
X-339661Y-172860D01*
Y-171334D01*
X-338511Y-170184D01*
Y-169364D01*
G03X-339341Y-167360I-2834J0D01*
G01X-350591Y-162756D02*
Y-158893D01*
G03X-350714Y-158596I-420J0D01*
G01X-351187Y-158122D01*
G02X-351310Y-157825I297J297D01*
G01Y-151829D01*
G02X-350511Y-149900I2729J0D01*
G01X-353740Y-162756D02*
Y-158893D01*
G02X-353617Y-158596I420J0D01*
G01X-353143Y-158122D01*
G03X-353020Y-157825I-297J297D01*
G01Y-151568D01*
G03X-353711Y-149900I-2359J0D01*
G01X-360039Y-162756D02*
Y-158893D01*
G03X-360162Y-158596I-420J0D01*
G01X-360636Y-158122D01*
G02X-360759Y-157825I297J297D01*
G01Y-136149D01*
G02X-360014Y-134350I2544J0D01*
G01X-363189Y-162756D02*
Y-158893D01*
G02X-363066Y-158596I420J0D01*
G01X-362592Y-158122D01*
G03X-362469Y-157825I-297J297D01*
G01Y-136149D01*
G03X-363214Y-134350I-2544J0D01*
G01X-253346Y-142362D02*
Y-147465D01*
X-252627Y-148185D01*
Y-153384D01*
G02X-253372Y-155183I-2544J0D01*
G01X-250197Y-142362D02*
Y-147416D01*
X-250917Y-148135D01*
Y-153384D01*
G03X-250172Y-155183I2544J0D01*
G01X-231299Y-142362D02*
Y-137362D01*
X-232021Y-136640D01*
Y-122070D01*
G03X-234891Y-119200I-2870J0D01*
G01X-236826D01*
G02X-238624Y-118455I0J2544D01*
G01X-234449Y-142362D02*
Y-137328D01*
X-233731Y-136610D01*
Y-122070D01*
G03X-234891Y-120910I-1160J0D01*
G01X-236826D01*
G03X-238624Y-121655I0J-2544D01*
G54D36*
X-1003346Y-36375D03*
X-960039D03*
X-133268D03*
X-89961D03*
G54D27*
X-1302441Y-79700D03*
X-1307559D03*
Y-74200D03*
X-1302441D03*
Y-68700D03*
X-1307559D03*
Y-63200D03*
X-1302441D03*
X-1307559Y-57700D03*
X-1302441D03*
X-1307559Y-52200D03*
X-1302441D03*
X-1307559Y-41200D03*
X-1302441D03*
Y-46700D03*
X-1307559D03*
Y-30200D03*
X-1302441D03*
X-1307559Y-35700D03*
X-1302441D03*
X-1187559Y-40500D03*
X-1182441D03*
X-1187559Y-46500D03*
X-1182441D03*
X-1187359Y-29400D03*
X-1187487Y-23450D03*
X-1182369D03*
X-1187359Y-34900D03*
X-1182369Y-18250D03*
X-1187487D03*
X-1187409Y-12128D03*
X-1182291D03*
X-1187359Y-5800D03*
Y0D03*
X-1168559Y-38500D03*
Y-49500D03*
Y-44000D03*
Y-33000D03*
X-1182241Y-29400D03*
X-1168487Y-26950D03*
X-1182241Y-34900D03*
X-1168487Y-10750D03*
Y-21750D03*
Y-16250D03*
X-1182241Y-5800D03*
X-1168487Y-5450D03*
X-1182241Y0D03*
X-1163441Y-38500D03*
Y-49500D03*
Y-44000D03*
Y-33000D03*
X-1163369Y-26950D03*
Y-10750D03*
Y-21750D03*
Y-16250D03*
Y-5450D03*
X-1053787Y-52850D03*
X-1048669D03*
X-1045441Y-34000D03*
X-1050559D03*
X-1045441Y-10000D03*
X-1050559D03*
X-1045550Y-16600D03*
X-1050650D03*
X-438959Y-74100D03*
X-433841D03*
Y-79600D03*
X-438959D03*
X-433841Y-68600D03*
X-438959D03*
Y-63100D03*
X-433841D03*
X-438959Y-57600D03*
X-433841D03*
X-438959Y-46600D03*
X-433841D03*
X-438959Y-52100D03*
X-433841D03*
X-438959Y-41100D03*
X-433841D03*
X-438959Y-35600D03*
X-433841D03*
Y-29500D03*
X-438959D03*
X-318059Y-42000D03*
Y-47500D03*
X-317859Y-36400D03*
X-317987Y-24950D03*
X-317859Y-30900D03*
X-317987Y-19750D03*
X-317859Y-7300D03*
X-317909Y-13628D03*
X-317859Y-1500D03*
X-312941Y-42000D03*
Y-47500D03*
X-312741Y-36400D03*
X-312869Y-24950D03*
X-312741Y-30900D03*
X-312869Y-19750D03*
X-312741Y-7300D03*
X-312791Y-13628D03*
X-312741Y-1500D03*
X-299259Y-38000D03*
X-294141D03*
Y-48800D03*
X-299259D03*
X-294141Y-43300D03*
X-299259D03*
X-294141Y-32500D03*
X-299259D03*
X-298987Y-25950D03*
X-293869D03*
Y-20750D03*
X-298987D03*
X-299131Y-15250D03*
X-294013D03*
Y-9750D03*
X-299131D03*
X-298987Y-4450D03*
X-293869D03*
X-182209Y-52350D03*
X-177091D03*
X-178959Y-34470D03*
X-179059Y-10000D03*
X-178850Y-16500D03*
X-173841Y-34470D03*
X-173941Y-10000D03*
X-173750Y-16500D03*
G54D18*
X-1545118Y-178189D03*
X-675039D03*
G54D46*
G01X-1189333Y-572500D02*
Y-565500D01*
X-1187667D01*
X-1187000Y-565850D01*
X-1186500Y-566317D01*
X-1186083Y-567017D01*
X-1185750Y-567833D01*
X-1185667Y-569000D01*
X-1185750Y-570167D01*
X-1186083Y-570983D01*
X-1186500Y-571684D01*
X-1187000Y-572150D01*
X-1187667Y-572500D01*
X-1189333D01*
G01X-1180700D02*
X-1181367Y-572383D01*
X-1181950Y-571917D01*
X-1182450Y-571217D01*
X-1182783Y-570400D01*
X-1182950Y-569467D01*
Y-568533D01*
X-1182783Y-567600D01*
X-1182450Y-566783D01*
X-1181950Y-566083D01*
X-1181367Y-565617D01*
X-1180700Y-565500D01*
X-1180033Y-565617D01*
X-1179450Y-566083D01*
X-1178950Y-566783D01*
X-1178617Y-567600D01*
X-1178450Y-568533D01*
Y-569467D01*
X-1178617Y-570400D01*
X-1178950Y-571217D01*
X-1179450Y-571917D01*
X-1180033Y-572383D01*
X-1180700Y-572500D01*
G01X-1172067Y-566083D02*
X-1172567Y-565733D01*
X-1173150Y-565500D01*
X-1173817D01*
X-1174567Y-565850D01*
X-1175150Y-566433D01*
X-1175567Y-567133D01*
X-1175900Y-568300D01*
X-1175983Y-569350D01*
X-1175817Y-570400D01*
X-1175567Y-571100D01*
X-1175067Y-571800D01*
X-1174483Y-572267D01*
X-1173900Y-572500D01*
X-1173317D01*
X-1172733Y-572267D01*
X-1172233Y-571917D01*
X-1171817Y-571450D01*
G01X-1168933Y-565500D02*
Y-570517D01*
X-1168600Y-571567D01*
X-1167933Y-572267D01*
X-1167100Y-572500D01*
X-1166267Y-572267D01*
X-1165600Y-571567D01*
X-1165267Y-570517D01*
Y-565500D01*
G01X-1162467Y-572500D02*
Y-565500D01*
X-1160300Y-571333D01*
X-1158133Y-565500D01*
Y-572500D01*
G01X-1151833D02*
X-1155167D01*
Y-565500D01*
X-1151833D01*
G01X-1153167Y-568883D02*
X-1155167D01*
G01X-1148617Y-572500D02*
Y-565500D01*
X-1144783Y-572500D01*
Y-565500D01*
G01X-1139900D02*
Y-572500D01*
G01X-1141817Y-565500D02*
X-1137983D01*
G01X-1128217Y-572500D02*
Y-565500D01*
X-1124383Y-572500D01*
Y-565500D01*
G01X-1121333D02*
Y-570517D01*
X-1121000Y-571567D01*
X-1120333Y-572267D01*
X-1119500Y-572500D01*
X-1118667Y-572267D01*
X-1118000Y-571567D01*
X-1117667Y-570517D01*
Y-565500D01*
G01X-1114867Y-572500D02*
Y-565500D01*
X-1112700Y-571333D01*
X-1110533Y-565500D01*
Y-572500D01*
G01X-1105233Y-568767D02*
X-1104900Y-568417D01*
X-1104650Y-567833D01*
X-1104483Y-567017D01*
X-1104650Y-566317D01*
X-1104983Y-565850D01*
X-1105567Y-565500D01*
X-1107817D01*
Y-572500D01*
X-1105067D01*
X-1104483Y-572033D01*
X-1104150Y-571333D01*
X-1103983Y-570517D01*
X-1104150Y-569700D01*
X-1104650Y-569000D01*
X-1105233Y-568767D01*
X-1107817D01*
G01X-1097433Y-572500D02*
X-1100767D01*
Y-565500D01*
X-1097433D01*
G01X-1098767Y-568883D02*
X-1100767D01*
G01X-1093967Y-572500D02*
Y-565500D01*
X-1091883D01*
X-1091217Y-565850D01*
X-1090800Y-566317D01*
X-1090633Y-567250D01*
X-1090800Y-568183D01*
X-1091300Y-568767D01*
X-1091883Y-569117D01*
X-1093967D01*
G01X-1091883D02*
X-1090633Y-572500D01*
G01X-1189250Y-531567D02*
X-1188583Y-532150D01*
X-1187833Y-532500D01*
X-1187167D01*
X-1186500Y-532150D01*
X-1186000Y-531567D01*
X-1185750Y-530750D01*
X-1185917Y-529933D01*
X-1186333Y-529233D01*
X-1187083Y-528767D01*
X-1188083Y-528533D01*
X-1188667Y-528067D01*
X-1188917Y-527250D01*
X-1188750Y-526433D01*
X-1188333Y-525850D01*
X-1187750Y-525500D01*
X-1187167D01*
X-1186583Y-525733D01*
X-1186083Y-526317D01*
G01X-1182450Y-532500D02*
Y-525500D01*
G01X-1178950D02*
Y-532500D01*
G01Y-529000D02*
X-1182450D01*
G01X-1172233Y-532500D02*
X-1175567D01*
Y-525500D01*
X-1172233D01*
G01X-1173567Y-528883D02*
X-1175567D01*
G01X-1165433Y-532500D02*
X-1168767D01*
Y-525500D01*
X-1165433D01*
G01X-1166767Y-528883D02*
X-1168767D01*
G01X-1160300Y-525500D02*
Y-532500D01*
G01X-1162217Y-525500D02*
X-1158383D01*
G01X-1146700D02*
Y-532500D01*
G01X-1148617Y-525500D02*
X-1144783D01*
G01X-1140900D02*
X-1138900D01*
G01X-1139900D02*
Y-532500D01*
G01X-1140900D02*
X-1138900D01*
G01X-1133100Y-525500D02*
Y-532500D01*
G01X-1135017Y-525500D02*
X-1131183D01*
G01X-1127967D02*
Y-532500D01*
X-1124633D01*
G01X-1117833D02*
X-1121167D01*
Y-525500D01*
X-1117833D01*
G01X-1119167Y-528883D02*
X-1121167D01*
G01X-1112700Y-532733D02*
X-1112867Y-532617D01*
Y-532383D01*
X-1112700Y-532267D01*
X-1112533Y-532383D01*
Y-532617D01*
X-1112700Y-532733D01*
G01Y-529584D02*
X-1112867Y-529467D01*
Y-529233D01*
X-1112700Y-529117D01*
X-1112533Y-529233D01*
Y-529467D01*
X-1112700Y-529584D01*
G01X-1187500Y-485500D02*
Y-492500D01*
G01X-1189417Y-485500D02*
X-1185583D01*
G01X-1181700D02*
X-1179700D01*
G01X-1180700D02*
Y-492500D01*
G01X-1181700D02*
X-1179700D01*
G01X-1173900Y-485500D02*
Y-492500D01*
G01X-1175817Y-485500D02*
X-1171983D01*
G01X-1168767D02*
Y-492500D01*
X-1165433D01*
G01X-1158633D02*
X-1161967D01*
Y-485500D01*
X-1158633D01*
G01X-1159967Y-488883D02*
X-1161967D01*
G01X-916667Y-570000D02*
Y-563000D01*
X-914583D01*
X-913917Y-563350D01*
X-913500Y-563817D01*
X-913333Y-564750D01*
X-913500Y-565683D01*
X-914000Y-566267D01*
X-914583Y-566617D01*
X-916667D01*
G01X-914583D02*
X-913333Y-570000D01*
G01X-906533D02*
X-909867D01*
Y-563000D01*
X-906533D01*
G01X-907867Y-566383D02*
X-909867D01*
G01X-903483Y-563000D02*
X-901400Y-570000D01*
X-899317Y-563000D01*
G01X-907850Y-451567D02*
X-907183Y-452150D01*
X-906433Y-452500D01*
X-905767D01*
X-905100Y-452150D01*
X-904600Y-451567D01*
X-904350Y-450750D01*
X-904517Y-449933D01*
X-904933Y-449233D01*
X-905683Y-448767D01*
X-906683Y-448533D01*
X-907267Y-448067D01*
X-907517Y-447250D01*
X-907350Y-446433D01*
X-906933Y-445850D01*
X-906350Y-445500D01*
X-905767D01*
X-905183Y-445733D01*
X-904683Y-446317D01*
G01X-897467Y-446083D02*
X-897967Y-445733D01*
X-898550Y-445500D01*
X-899217D01*
X-899967Y-445850D01*
X-900550Y-446433D01*
X-900967Y-447133D01*
X-901300Y-448300D01*
X-901383Y-449350D01*
X-901217Y-450400D01*
X-900967Y-451100D01*
X-900467Y-451800D01*
X-899883Y-452267D01*
X-899300Y-452500D01*
X-898717D01*
X-898133Y-452267D01*
X-897633Y-451917D01*
X-897217Y-451450D01*
G01X-894583Y-452500D02*
X-892500Y-445500D01*
X-890417Y-452500D01*
G01X-891167Y-450050D02*
X-893833D01*
G01X-887367Y-445500D02*
Y-452500D01*
X-884033D01*
G01X-877233D02*
X-880567D01*
Y-445500D01*
X-877233D01*
G01X-878567Y-448883D02*
X-880567D01*
G01X-874333Y-572500D02*
Y-565500D01*
X-872667D01*
X-872000Y-565850D01*
X-871500Y-566317D01*
X-871083Y-567017D01*
X-870750Y-567833D01*
X-870667Y-569000D01*
X-870750Y-570167D01*
X-871083Y-570983D01*
X-871500Y-571684D01*
X-872000Y-572150D01*
X-872667Y-572500D01*
X-874333D01*
G01X-866700Y-565500D02*
X-864700D01*
G01X-865700D02*
Y-572500D01*
G01X-866700D02*
X-864700D01*
G01X-860650Y-571567D02*
X-859983Y-572150D01*
X-859233Y-572500D01*
X-858567D01*
X-857900Y-572150D01*
X-857400Y-571567D01*
X-857150Y-570750D01*
X-857317Y-569933D01*
X-857733Y-569233D01*
X-858483Y-568767D01*
X-859483Y-568533D01*
X-860067Y-568067D01*
X-860317Y-567250D01*
X-860150Y-566433D01*
X-859733Y-565850D01*
X-859150Y-565500D01*
X-858567D01*
X-857983Y-565733D01*
X-857483Y-566317D01*
G01X-850267Y-566083D02*
X-850767Y-565733D01*
X-851350Y-565500D01*
X-852017D01*
X-852767Y-565850D01*
X-853350Y-566433D01*
X-853767Y-567133D01*
X-854100Y-568300D01*
X-854183Y-569350D01*
X-854017Y-570400D01*
X-853767Y-571100D01*
X-853267Y-571800D01*
X-852683Y-572267D01*
X-852100Y-572500D01*
X-851517D01*
X-850933Y-572267D01*
X-850433Y-571917D01*
X-850017Y-571450D01*
G01X-846967Y-565500D02*
Y-572500D01*
X-843633D01*
G01X-838500D02*
X-839167Y-572383D01*
X-839750Y-571917D01*
X-840250Y-571217D01*
X-840583Y-570400D01*
X-840750Y-569467D01*
Y-568533D01*
X-840583Y-567600D01*
X-840250Y-566783D01*
X-839750Y-566083D01*
X-839167Y-565617D01*
X-838500Y-565500D01*
X-837833Y-565617D01*
X-837250Y-566083D01*
X-836750Y-566783D01*
X-836417Y-567600D01*
X-836250Y-568533D01*
Y-569467D01*
X-836417Y-570400D01*
X-836750Y-571217D01*
X-837250Y-571917D01*
X-837833Y-572383D01*
X-838500Y-572500D01*
G01X-833450Y-571567D02*
X-832783Y-572150D01*
X-832033Y-572500D01*
X-831367D01*
X-830700Y-572150D01*
X-830200Y-571567D01*
X-829950Y-570750D01*
X-830117Y-569933D01*
X-830533Y-569233D01*
X-831283Y-568767D01*
X-832283Y-568533D01*
X-832867Y-568067D01*
X-833117Y-567250D01*
X-832950Y-566433D01*
X-832533Y-565850D01*
X-831950Y-565500D01*
X-831367D01*
X-830783Y-565733D01*
X-830283Y-566317D01*
G01X-823233Y-572500D02*
X-826567D01*
Y-565500D01*
X-823233D01*
G01X-824567Y-568883D02*
X-826567D01*
G01X-819933Y-572500D02*
Y-565500D01*
X-818267D01*
X-817600Y-565850D01*
X-817100Y-566317D01*
X-816683Y-567017D01*
X-816350Y-567833D01*
X-816267Y-569000D01*
X-816350Y-570167D01*
X-816683Y-570983D01*
X-817100Y-571684D01*
X-817600Y-572150D01*
X-818267Y-572500D01*
X-819933D01*
G01X-807000Y-565500D02*
X-805833Y-572500D01*
X-804500Y-565500D01*
X-803167Y-572500D01*
X-802000Y-565500D01*
G01X-798700D02*
X-796700D01*
G01X-797700D02*
Y-572500D01*
G01X-798700D02*
X-796700D01*
G01X-790900Y-565500D02*
Y-572500D01*
G01X-792817Y-565500D02*
X-788983D01*
G01X-785850Y-572500D02*
Y-565500D01*
G01X-782350D02*
Y-572500D01*
G01Y-569000D02*
X-785850D01*
G01X-777300Y-572500D02*
X-777967Y-572383D01*
X-778550Y-571917D01*
X-779050Y-571217D01*
X-779383Y-570400D01*
X-779550Y-569467D01*
Y-568533D01*
X-779383Y-567600D01*
X-779050Y-566783D01*
X-778550Y-566083D01*
X-777967Y-565617D01*
X-777300Y-565500D01*
X-776633Y-565617D01*
X-776050Y-566083D01*
X-775550Y-566783D01*
X-775217Y-567600D01*
X-775050Y-568533D01*
Y-569467D01*
X-775217Y-570400D01*
X-775550Y-571217D01*
X-776050Y-571917D01*
X-776633Y-572383D01*
X-777300Y-572500D01*
G01X-772333Y-565500D02*
Y-570517D01*
X-772000Y-571567D01*
X-771333Y-572267D01*
X-770500Y-572500D01*
X-769667Y-572267D01*
X-769000Y-571567D01*
X-768667Y-570517D01*
Y-565500D01*
G01X-763700D02*
Y-572500D01*
G01X-765617Y-565500D02*
X-761783D01*
G01X-750100D02*
Y-572500D01*
G01X-752017Y-565500D02*
X-748183D01*
G01X-745050Y-572500D02*
Y-565500D01*
G01X-741550D02*
Y-572500D01*
G01Y-569000D02*
X-745050D01*
G01X-734833Y-572500D02*
X-738167D01*
Y-565500D01*
X-734833D01*
G01X-736167Y-568883D02*
X-738167D01*
G01X-724567Y-572500D02*
Y-565500D01*
X-722567D01*
X-721900Y-565850D01*
X-721400Y-566667D01*
X-721233Y-567600D01*
X-721400Y-568533D01*
X-721817Y-569233D01*
X-722567Y-569584D01*
X-724567D01*
G01X-717767Y-572500D02*
Y-565500D01*
X-715683D01*
X-715017Y-565850D01*
X-714600Y-566317D01*
X-714433Y-567250D01*
X-714600Y-568183D01*
X-715100Y-568767D01*
X-715683Y-569117D01*
X-717767D01*
G01X-715683D02*
X-714433Y-572500D01*
G01X-710300Y-565500D02*
X-708300D01*
G01X-709300D02*
Y-572500D01*
G01X-710300D02*
X-708300D01*
G01X-702500D02*
X-703167Y-572383D01*
X-703750Y-571917D01*
X-704250Y-571217D01*
X-704583Y-570400D01*
X-704750Y-569467D01*
Y-568533D01*
X-704583Y-567600D01*
X-704250Y-566783D01*
X-703750Y-566083D01*
X-703167Y-565617D01*
X-702500Y-565500D01*
X-701833Y-565617D01*
X-701250Y-566083D01*
X-700750Y-566783D01*
X-700417Y-567600D01*
X-700250Y-568533D01*
Y-569467D01*
X-700417Y-570400D01*
X-700750Y-571217D01*
X-701250Y-571917D01*
X-701833Y-572383D01*
X-702500Y-572500D01*
G01X-697367D02*
Y-565500D01*
X-695283D01*
X-694617Y-565850D01*
X-694200Y-566317D01*
X-694033Y-567250D01*
X-694200Y-568183D01*
X-694700Y-568767D01*
X-695283Y-569117D01*
X-697367D01*
G01X-695283D02*
X-694033Y-572500D01*
G01X-684600Y-565500D02*
X-683433Y-572500D01*
X-682100Y-565500D01*
X-680767Y-572500D01*
X-679600Y-565500D01*
G01X-676967Y-572500D02*
Y-565500D01*
X-674883D01*
X-674217Y-565850D01*
X-673800Y-566317D01*
X-673633Y-567250D01*
X-673800Y-568183D01*
X-674300Y-568767D01*
X-674883Y-569117D01*
X-676967D01*
G01X-674883D02*
X-673633Y-572500D01*
G01X-669500Y-565500D02*
X-667500D01*
G01X-668500D02*
Y-572500D01*
G01X-669500D02*
X-667500D01*
G01X-661700Y-565500D02*
Y-572500D01*
G01X-663617Y-565500D02*
X-659783D01*
G01X-654900D02*
Y-572500D01*
G01X-656817Y-565500D02*
X-652983D01*
G01X-646433Y-572500D02*
X-649767D01*
Y-565500D01*
X-646433D01*
G01X-647767Y-568883D02*
X-649767D01*
G01X-643217Y-572500D02*
Y-565500D01*
X-639383Y-572500D01*
Y-565500D01*
G01X-625867Y-566083D02*
X-626367Y-565733D01*
X-626950Y-565500D01*
X-627617D01*
X-628367Y-565850D01*
X-628950Y-566433D01*
X-629367Y-567133D01*
X-629700Y-568300D01*
X-629783Y-569350D01*
X-629617Y-570400D01*
X-629367Y-571100D01*
X-628867Y-571800D01*
X-628283Y-572267D01*
X-627700Y-572500D01*
X-627117D01*
X-626533Y-572267D01*
X-626033Y-571917D01*
X-625617Y-571450D01*
G01X-620900Y-572500D02*
X-621567Y-572383D01*
X-622150Y-571917D01*
X-622650Y-571217D01*
X-622983Y-570400D01*
X-623150Y-569467D01*
Y-568533D01*
X-622983Y-567600D01*
X-622650Y-566783D01*
X-622150Y-566083D01*
X-621567Y-565617D01*
X-620900Y-565500D01*
X-620233Y-565617D01*
X-619650Y-566083D01*
X-619150Y-566783D01*
X-618817Y-567600D01*
X-618650Y-568533D01*
Y-569467D01*
X-618817Y-570400D01*
X-619150Y-571217D01*
X-619650Y-571917D01*
X-620233Y-572383D01*
X-620900Y-572500D01*
G01X-616017D02*
Y-565500D01*
X-612183Y-572500D01*
Y-565500D01*
G01X-609050Y-571567D02*
X-608383Y-572150D01*
X-607633Y-572500D01*
X-606967D01*
X-606300Y-572150D01*
X-605800Y-571567D01*
X-605550Y-570750D01*
X-605717Y-569933D01*
X-606133Y-569233D01*
X-606883Y-568767D01*
X-607883Y-568533D01*
X-608467Y-568067D01*
X-608717Y-567250D01*
X-608550Y-566433D01*
X-608133Y-565850D01*
X-607550Y-565500D01*
X-606967D01*
X-606383Y-565733D01*
X-605883Y-566317D01*
G01X-598833Y-572500D02*
X-602167D01*
Y-565500D01*
X-598833D01*
G01X-600167Y-568883D02*
X-602167D01*
G01X-595617Y-572500D02*
Y-565500D01*
X-591783Y-572500D01*
Y-565500D01*
G01X-586900D02*
Y-572500D01*
G01X-588817Y-565500D02*
X-584983D01*
G01X-872500Y-587500D02*
X-873167Y-587383D01*
X-873750Y-586917D01*
X-874250Y-586217D01*
X-874583Y-585400D01*
X-874750Y-584467D01*
Y-583533D01*
X-874583Y-582600D01*
X-874250Y-581783D01*
X-873750Y-581083D01*
X-873167Y-580617D01*
X-872500Y-580500D01*
X-871833Y-580617D01*
X-871250Y-581083D01*
X-870750Y-581783D01*
X-870417Y-582600D01*
X-870250Y-583533D01*
Y-584467D01*
X-870417Y-585400D01*
X-870750Y-586217D01*
X-871250Y-586917D01*
X-871833Y-587383D01*
X-872500Y-587500D01*
G01X-867283D02*
Y-580500D01*
X-864117D01*
G01X-865283Y-583883D02*
X-867283D01*
G01X-854267Y-587500D02*
Y-580500D01*
X-852100Y-586333D01*
X-849933Y-580500D01*
Y-587500D01*
G01X-846300Y-580500D02*
X-844300D01*
G01X-845300D02*
Y-587500D01*
G01X-846300D02*
X-844300D01*
G01X-836667Y-581083D02*
X-837167Y-580733D01*
X-837750Y-580500D01*
X-838417D01*
X-839167Y-580850D01*
X-839750Y-581433D01*
X-840167Y-582133D01*
X-840500Y-583300D01*
X-840583Y-584350D01*
X-840417Y-585400D01*
X-840167Y-586100D01*
X-839667Y-586800D01*
X-839083Y-587267D01*
X-838500Y-587500D01*
X-837917D01*
X-837333Y-587267D01*
X-836833Y-586917D01*
X-836417Y-586450D01*
G01X-833367Y-587500D02*
Y-580500D01*
X-831283D01*
X-830617Y-580850D01*
X-830200Y-581317D01*
X-830033Y-582250D01*
X-830200Y-583183D01*
X-830700Y-583767D01*
X-831283Y-584117D01*
X-833367D01*
G01X-831283D02*
X-830033Y-587500D01*
G01X-824900D02*
X-825567Y-587383D01*
X-826150Y-586917D01*
X-826650Y-586217D01*
X-826983Y-585400D01*
X-827150Y-584467D01*
Y-583533D01*
X-826983Y-582600D01*
X-826650Y-581783D01*
X-826150Y-581083D01*
X-825567Y-580617D01*
X-824900Y-580500D01*
X-824233Y-580617D01*
X-823650Y-581083D01*
X-823150Y-581783D01*
X-822817Y-582600D01*
X-822650Y-583533D01*
Y-584467D01*
X-822817Y-585400D01*
X-823150Y-586217D01*
X-823650Y-586917D01*
X-824233Y-587383D01*
X-824900Y-587500D01*
G01X-819850Y-586567D02*
X-819183Y-587150D01*
X-818433Y-587500D01*
X-817767D01*
X-817100Y-587150D01*
X-816600Y-586567D01*
X-816350Y-585750D01*
X-816517Y-584933D01*
X-816933Y-584233D01*
X-817683Y-583767D01*
X-818683Y-583533D01*
X-819267Y-583067D01*
X-819517Y-582250D01*
X-819350Y-581433D01*
X-818933Y-580850D01*
X-818350Y-580500D01*
X-817767D01*
X-817183Y-580733D01*
X-816683Y-581317D01*
G01X-811300Y-587500D02*
X-811967Y-587383D01*
X-812550Y-586917D01*
X-813050Y-586217D01*
X-813383Y-585400D01*
X-813550Y-584467D01*
Y-583533D01*
X-813383Y-582600D01*
X-813050Y-581783D01*
X-812550Y-581083D01*
X-811967Y-580617D01*
X-811300Y-580500D01*
X-810633Y-580617D01*
X-810050Y-581083D01*
X-809550Y-581783D01*
X-809217Y-582600D01*
X-809050Y-583533D01*
Y-584467D01*
X-809217Y-585400D01*
X-809550Y-586217D01*
X-810050Y-586917D01*
X-810633Y-587383D01*
X-811300Y-587500D01*
G01X-806083D02*
Y-580500D01*
X-802917D01*
G01X-804083Y-583883D02*
X-806083D01*
G01X-797700Y-580500D02*
Y-587500D01*
G01X-799617Y-580500D02*
X-795783D01*
G01X-782267Y-581083D02*
X-782767Y-580733D01*
X-783350Y-580500D01*
X-784017D01*
X-784767Y-580850D01*
X-785350Y-581433D01*
X-785767Y-582133D01*
X-786100Y-583300D01*
X-786183Y-584350D01*
X-786017Y-585400D01*
X-785767Y-586100D01*
X-785267Y-586800D01*
X-784683Y-587267D01*
X-784100Y-587500D01*
X-783517D01*
X-782933Y-587267D01*
X-782433Y-586917D01*
X-782017Y-586450D01*
G01X-777300Y-587500D02*
X-777967Y-587383D01*
X-778550Y-586917D01*
X-779050Y-586217D01*
X-779383Y-585400D01*
X-779550Y-584467D01*
Y-583533D01*
X-779383Y-582600D01*
X-779050Y-581783D01*
X-778550Y-581083D01*
X-777967Y-580617D01*
X-777300Y-580500D01*
X-776633Y-580617D01*
X-776050Y-581083D01*
X-775550Y-581783D01*
X-775217Y-582600D01*
X-775050Y-583533D01*
Y-584467D01*
X-775217Y-585400D01*
X-775550Y-586217D01*
X-776050Y-586917D01*
X-776633Y-587383D01*
X-777300Y-587500D01*
G01X-772167D02*
Y-580500D01*
X-770083D01*
X-769417Y-580850D01*
X-769000Y-581317D01*
X-768833Y-582250D01*
X-769000Y-583183D01*
X-769500Y-583767D01*
X-770083Y-584117D01*
X-772167D01*
G01X-770083D02*
X-768833Y-587500D01*
G01X-765367D02*
Y-580500D01*
X-763367D01*
X-762700Y-580850D01*
X-762200Y-581667D01*
X-762033Y-582600D01*
X-762200Y-583533D01*
X-762617Y-584233D01*
X-763367Y-584584D01*
X-765367D01*
G01X-756900Y-587500D02*
X-757567Y-587383D01*
X-758150Y-586917D01*
X-758650Y-586217D01*
X-758983Y-585400D01*
X-759150Y-584467D01*
Y-583533D01*
X-758983Y-582600D01*
X-758650Y-581783D01*
X-758150Y-581083D01*
X-757567Y-580617D01*
X-756900Y-580500D01*
X-756233Y-580617D01*
X-755650Y-581083D01*
X-755150Y-581783D01*
X-754817Y-582600D01*
X-754650Y-583533D01*
Y-584467D01*
X-754817Y-585400D01*
X-755150Y-586217D01*
X-755650Y-586917D01*
X-756233Y-587383D01*
X-756900Y-587500D01*
G01X-751767D02*
Y-580500D01*
X-749683D01*
X-749017Y-580850D01*
X-748600Y-581317D01*
X-748433Y-582250D01*
X-748600Y-583183D01*
X-749100Y-583767D01*
X-749683Y-584117D01*
X-751767D01*
G01X-749683D02*
X-748433Y-587500D01*
G01X-745383D02*
X-743300Y-580500D01*
X-741217Y-587500D01*
G01X-741967Y-585050D02*
X-744633D01*
G01X-736500Y-580500D02*
Y-587500D01*
G01X-738417Y-580500D02*
X-734583D01*
G01X-730700D02*
X-728700D01*
G01X-729700D02*
Y-587500D01*
G01X-730700D02*
X-728700D01*
G01X-722900D02*
X-723567Y-587383D01*
X-724150Y-586917D01*
X-724650Y-586217D01*
X-724983Y-585400D01*
X-725150Y-584467D01*
Y-583533D01*
X-724983Y-582600D01*
X-724650Y-581783D01*
X-724150Y-581083D01*
X-723567Y-580617D01*
X-722900Y-580500D01*
X-722233Y-580617D01*
X-721650Y-581083D01*
X-721150Y-581783D01*
X-720817Y-582600D01*
X-720650Y-583533D01*
Y-584467D01*
X-720817Y-585400D01*
X-721150Y-586217D01*
X-721650Y-586917D01*
X-722233Y-587383D01*
X-722900Y-587500D01*
G01X-718017D02*
Y-580500D01*
X-714183Y-587500D01*
Y-580500D01*
G01X-709300Y-587733D02*
X-709467Y-587617D01*
Y-587383D01*
X-709300Y-587267D01*
X-709133Y-587383D01*
Y-587617D01*
X-709300Y-587733D01*
G01X-870667Y-551083D02*
X-871167Y-550733D01*
X-871750Y-550500D01*
X-872417D01*
X-873167Y-550850D01*
X-873750Y-551433D01*
X-874167Y-552133D01*
X-874500Y-553300D01*
X-874583Y-554350D01*
X-874417Y-555400D01*
X-874167Y-556100D01*
X-873667Y-556800D01*
X-873083Y-557267D01*
X-872500Y-557500D01*
X-871917D01*
X-871333Y-557267D01*
X-870833Y-556917D01*
X-870417Y-556450D01*
G01X-865700Y-557500D02*
X-866367Y-557383D01*
X-866950Y-556917D01*
X-867450Y-556217D01*
X-867783Y-555400D01*
X-867950Y-554467D01*
Y-553533D01*
X-867783Y-552600D01*
X-867450Y-551783D01*
X-866950Y-551083D01*
X-866367Y-550617D01*
X-865700Y-550500D01*
X-865033Y-550617D01*
X-864450Y-551083D01*
X-863950Y-551783D01*
X-863617Y-552600D01*
X-863450Y-553533D01*
Y-554467D01*
X-863617Y-555400D01*
X-863950Y-556217D01*
X-864450Y-556917D01*
X-865033Y-557383D01*
X-865700Y-557500D01*
G01X-860817D02*
Y-550500D01*
X-856983Y-557500D01*
Y-550500D01*
G01X-853683Y-557500D02*
Y-550500D01*
X-850517D01*
G01X-851683Y-553883D02*
X-853683D01*
G01X-846300Y-550500D02*
X-844300D01*
G01X-845300D02*
Y-557500D01*
G01X-846300D02*
X-844300D01*
G01X-840333D02*
Y-550500D01*
X-838667D01*
X-838000Y-550850D01*
X-837500Y-551317D01*
X-837083Y-552017D01*
X-836750Y-552833D01*
X-836667Y-554000D01*
X-836750Y-555167D01*
X-837083Y-555983D01*
X-837500Y-556684D01*
X-838000Y-557150D01*
X-838667Y-557500D01*
X-840333D01*
G01X-830033D02*
X-833367D01*
Y-550500D01*
X-830033D01*
G01X-831367Y-553883D02*
X-833367D01*
G01X-826817Y-557500D02*
Y-550500D01*
X-822983Y-557500D01*
Y-550500D01*
G01X-816267Y-551083D02*
X-816767Y-550733D01*
X-817350Y-550500D01*
X-818017D01*
X-818767Y-550850D01*
X-819350Y-551433D01*
X-819767Y-552133D01*
X-820100Y-553300D01*
X-820183Y-554350D01*
X-820017Y-555400D01*
X-819767Y-556100D01*
X-819267Y-556800D01*
X-818683Y-557267D01*
X-818100Y-557500D01*
X-817517D01*
X-816933Y-557267D01*
X-816433Y-556917D01*
X-816017Y-556450D01*
G01X-809633Y-557500D02*
X-812967D01*
Y-550500D01*
X-809633D01*
G01X-810967Y-553883D02*
X-812967D01*
G01X-799783Y-557500D02*
X-797700Y-550500D01*
X-795617Y-557500D01*
G01X-796367Y-555050D02*
X-799033D01*
G01X-792817Y-557500D02*
Y-550500D01*
X-788983Y-557500D01*
Y-550500D01*
G01X-785933Y-557500D02*
Y-550500D01*
X-784267D01*
X-783600Y-550850D01*
X-783100Y-551317D01*
X-782683Y-552017D01*
X-782350Y-552833D01*
X-782267Y-554000D01*
X-782350Y-555167D01*
X-782683Y-555983D01*
X-783100Y-556684D01*
X-783600Y-557150D01*
X-784267Y-557500D01*
X-785933D01*
G01X-771500Y-550500D02*
X-769500D01*
G01X-770500D02*
Y-557500D01*
G01X-771500D02*
X-769500D01*
G01X-763700Y-550500D02*
Y-557500D01*
G01X-765617Y-550500D02*
X-761783D01*
G01X-758650Y-556567D02*
X-757983Y-557150D01*
X-757233Y-557500D01*
X-756567D01*
X-755900Y-557150D01*
X-755400Y-556567D01*
X-755150Y-555750D01*
X-755317Y-554933D01*
X-755733Y-554233D01*
X-756483Y-553767D01*
X-757483Y-553533D01*
X-758067Y-553067D01*
X-758317Y-552250D01*
X-758150Y-551433D01*
X-757733Y-550850D01*
X-757150Y-550500D01*
X-756567D01*
X-755983Y-550733D01*
X-755483Y-551317D01*
G01X-741467Y-551083D02*
X-741967Y-550733D01*
X-742550Y-550500D01*
X-743217D01*
X-743967Y-550850D01*
X-744550Y-551433D01*
X-744967Y-552133D01*
X-745300Y-553300D01*
X-745383Y-554350D01*
X-745217Y-555400D01*
X-744967Y-556100D01*
X-744467Y-556800D01*
X-743883Y-557267D01*
X-743300Y-557500D01*
X-742717D01*
X-742133Y-557267D01*
X-741633Y-556917D01*
X-741217Y-556450D01*
G01X-736500Y-557500D02*
X-737167Y-557383D01*
X-737750Y-556917D01*
X-738250Y-556217D01*
X-738583Y-555400D01*
X-738750Y-554467D01*
Y-553533D01*
X-738583Y-552600D01*
X-738250Y-551783D01*
X-737750Y-551083D01*
X-737167Y-550617D01*
X-736500Y-550500D01*
X-735833Y-550617D01*
X-735250Y-551083D01*
X-734750Y-551783D01*
X-734417Y-552600D01*
X-734250Y-553533D01*
Y-554467D01*
X-734417Y-555400D01*
X-734750Y-556217D01*
X-735250Y-556917D01*
X-735833Y-557383D01*
X-736500Y-557500D01*
G01X-731617D02*
Y-550500D01*
X-727783Y-557500D01*
Y-550500D01*
G01X-722900D02*
Y-557500D01*
G01X-724817Y-550500D02*
X-720983D01*
G01X-714433Y-557500D02*
X-717767D01*
Y-550500D01*
X-714433D01*
G01X-715767Y-553883D02*
X-717767D01*
G01X-711217Y-557500D02*
Y-550500D01*
X-707383Y-557500D01*
Y-550500D01*
G01X-702500D02*
Y-557500D01*
G01X-704417Y-550500D02*
X-700583D01*
G01X-697450Y-556567D02*
X-696783Y-557150D01*
X-696033Y-557500D01*
X-695367D01*
X-694700Y-557150D01*
X-694200Y-556567D01*
X-693950Y-555750D01*
X-694117Y-554933D01*
X-694533Y-554233D01*
X-695283Y-553767D01*
X-696283Y-553533D01*
X-696867Y-553067D01*
X-697117Y-552250D01*
X-696950Y-551433D01*
X-696533Y-550850D01*
X-695950Y-550500D01*
X-695367D01*
X-694783Y-550733D01*
X-694283Y-551317D01*
G01X-684267Y-557500D02*
Y-550500D01*
X-682100Y-556333D01*
X-679933Y-550500D01*
Y-557500D01*
G01X-677383D02*
X-675300Y-550500D01*
X-673217Y-557500D01*
G01X-673967Y-555050D02*
X-676633D01*
G01X-668500Y-557500D02*
Y-554350D01*
X-670167Y-550500D01*
G01X-666833D02*
X-668500Y-554350D01*
G01X-656817Y-557500D02*
Y-550500D01*
X-652983Y-557500D01*
Y-550500D01*
G01X-648100Y-557500D02*
X-648767Y-557383D01*
X-649350Y-556917D01*
X-649850Y-556217D01*
X-650183Y-555400D01*
X-650350Y-554467D01*
Y-553533D01*
X-650183Y-552600D01*
X-649850Y-551783D01*
X-649350Y-551083D01*
X-648767Y-550617D01*
X-648100Y-550500D01*
X-647433Y-550617D01*
X-646850Y-551083D01*
X-646350Y-551783D01*
X-646017Y-552600D01*
X-645850Y-553533D01*
Y-554467D01*
X-646017Y-555400D01*
X-646350Y-556217D01*
X-646850Y-556917D01*
X-647433Y-557383D01*
X-648100Y-557500D01*
G01X-641300Y-550500D02*
Y-557500D01*
G01X-643217Y-550500D02*
X-639383D01*
G01X-627033Y-553767D02*
X-626700Y-553417D01*
X-626450Y-552833D01*
X-626283Y-552017D01*
X-626450Y-551317D01*
X-626783Y-550850D01*
X-627367Y-550500D01*
X-629617D01*
Y-557500D01*
X-626867D01*
X-626283Y-557033D01*
X-625950Y-556333D01*
X-625783Y-555517D01*
X-625950Y-554700D01*
X-626450Y-554000D01*
X-627033Y-553767D01*
X-629617D01*
G01X-619233Y-557500D02*
X-622567D01*
Y-550500D01*
X-619233D01*
G01X-620567Y-553883D02*
X-622567D01*
G01X-870667Y-536083D02*
X-871167Y-535733D01*
X-871750Y-535500D01*
X-872417D01*
X-873167Y-535850D01*
X-873750Y-536433D01*
X-874167Y-537133D01*
X-874500Y-538300D01*
X-874583Y-539350D01*
X-874417Y-540400D01*
X-874167Y-541100D01*
X-873667Y-541800D01*
X-873083Y-542267D01*
X-872500Y-542500D01*
X-871917D01*
X-871333Y-542267D01*
X-870833Y-541917D01*
X-870417Y-541450D01*
G01X-865700Y-542500D02*
X-866367Y-542383D01*
X-866950Y-541917D01*
X-867450Y-541217D01*
X-867783Y-540400D01*
X-867950Y-539467D01*
Y-538533D01*
X-867783Y-537600D01*
X-867450Y-536783D01*
X-866950Y-536083D01*
X-866367Y-535617D01*
X-865700Y-535500D01*
X-865033Y-535617D01*
X-864450Y-536083D01*
X-863950Y-536783D01*
X-863617Y-537600D01*
X-863450Y-538533D01*
Y-539467D01*
X-863617Y-540400D01*
X-863950Y-541217D01*
X-864450Y-541917D01*
X-865033Y-542383D01*
X-865700Y-542500D01*
G01X-860567D02*
Y-535500D01*
X-858483D01*
X-857817Y-535850D01*
X-857400Y-536317D01*
X-857233Y-537250D01*
X-857400Y-538183D01*
X-857900Y-538767D01*
X-858483Y-539117D01*
X-860567D01*
G01X-858483D02*
X-857233Y-542500D01*
G01X-853767D02*
Y-535500D01*
X-851767D01*
X-851100Y-535850D01*
X-850600Y-536667D01*
X-850433Y-537600D01*
X-850600Y-538533D01*
X-851017Y-539233D01*
X-851767Y-539584D01*
X-853767D01*
G01X-845300Y-542500D02*
X-845967Y-542383D01*
X-846550Y-541917D01*
X-847050Y-541217D01*
X-847383Y-540400D01*
X-847550Y-539467D01*
Y-538533D01*
X-847383Y-537600D01*
X-847050Y-536783D01*
X-846550Y-536083D01*
X-845967Y-535617D01*
X-845300Y-535500D01*
X-844633Y-535617D01*
X-844050Y-536083D01*
X-843550Y-536783D01*
X-843217Y-537600D01*
X-843050Y-538533D01*
Y-539467D01*
X-843217Y-540400D01*
X-843550Y-541217D01*
X-844050Y-541917D01*
X-844633Y-542383D01*
X-845300Y-542500D01*
G01X-840167D02*
Y-535500D01*
X-838083D01*
X-837417Y-535850D01*
X-837000Y-536317D01*
X-836833Y-537250D01*
X-837000Y-538183D01*
X-837500Y-538767D01*
X-838083Y-539117D01*
X-840167D01*
G01X-838083D02*
X-836833Y-542500D01*
G01X-833783D02*
X-831700Y-535500D01*
X-829617Y-542500D01*
G01X-830367Y-540050D02*
X-833033D01*
G01X-824900Y-535500D02*
Y-542500D01*
G01X-826817Y-535500D02*
X-822983D01*
G01X-819100D02*
X-817100D01*
G01X-818100D02*
Y-542500D01*
G01X-819100D02*
X-817100D01*
G01X-811300D02*
X-811967Y-542383D01*
X-812550Y-541917D01*
X-813050Y-541217D01*
X-813383Y-540400D01*
X-813550Y-539467D01*
Y-538533D01*
X-813383Y-537600D01*
X-813050Y-536783D01*
X-812550Y-536083D01*
X-811967Y-535617D01*
X-811300Y-535500D01*
X-810633Y-535617D01*
X-810050Y-536083D01*
X-809550Y-536783D01*
X-809217Y-537600D01*
X-809050Y-538533D01*
Y-539467D01*
X-809217Y-540400D01*
X-809550Y-541217D01*
X-810050Y-541917D01*
X-810633Y-542383D01*
X-811300Y-542500D01*
G01X-806417D02*
Y-535500D01*
X-802583Y-542500D01*
Y-535500D01*
G01X-797700Y-542733D02*
X-797867Y-542617D01*
Y-542383D01*
X-797700Y-542267D01*
X-797533Y-542383D01*
Y-542617D01*
X-797700Y-542733D01*
G01X-784100Y-535500D02*
Y-542500D01*
G01X-786017Y-535500D02*
X-782183D01*
G01X-779050Y-542500D02*
Y-535500D01*
G01X-775550D02*
Y-542500D01*
G01Y-539000D02*
X-779050D01*
G01X-771500Y-535500D02*
X-769500D01*
G01X-770500D02*
Y-542500D01*
G01X-771500D02*
X-769500D01*
G01X-765450Y-541567D02*
X-764783Y-542150D01*
X-764033Y-542500D01*
X-763367D01*
X-762700Y-542150D01*
X-762200Y-541567D01*
X-761950Y-540750D01*
X-762117Y-539933D01*
X-762533Y-539233D01*
X-763283Y-538767D01*
X-764283Y-538533D01*
X-764867Y-538067D01*
X-765117Y-537250D01*
X-764950Y-536433D01*
X-764533Y-535850D01*
X-763950Y-535500D01*
X-763367D01*
X-762783Y-535733D01*
X-762283Y-536317D01*
G01X-751933Y-542500D02*
Y-535500D01*
X-750267D01*
X-749600Y-535850D01*
X-749100Y-536317D01*
X-748683Y-537017D01*
X-748350Y-537833D01*
X-748267Y-539000D01*
X-748350Y-540167D01*
X-748683Y-540983D01*
X-749100Y-541684D01*
X-749600Y-542150D01*
X-750267Y-542500D01*
X-751933D01*
G01X-744967D02*
Y-535500D01*
X-742883D01*
X-742217Y-535850D01*
X-741800Y-536317D01*
X-741633Y-537250D01*
X-741800Y-538183D01*
X-742300Y-538767D01*
X-742883Y-539117D01*
X-744967D01*
G01X-742883D02*
X-741633Y-542500D01*
G01X-738583D02*
X-736500Y-535500D01*
X-734417Y-542500D01*
G01X-735167Y-540050D02*
X-737833D01*
G01X-732200Y-535500D02*
X-731033Y-542500D01*
X-729700Y-535500D01*
X-728367Y-542500D01*
X-727200Y-535500D01*
G01X-723900D02*
X-721900D01*
G01X-722900D02*
Y-542500D01*
G01X-723900D02*
X-721900D01*
G01X-718017D02*
Y-535500D01*
X-714183Y-542500D01*
Y-535500D01*
G01X-708800Y-539000D02*
X-707133D01*
Y-541100D01*
X-707633Y-541800D01*
X-708217Y-542267D01*
X-709050Y-542500D01*
X-709883Y-542267D01*
X-710467Y-541800D01*
X-710967Y-541100D01*
X-711300Y-540283D01*
X-711467Y-539350D01*
Y-538533D01*
X-711300Y-537833D01*
X-710967Y-537017D01*
X-710467Y-536317D01*
X-709967Y-535850D01*
X-709300Y-535500D01*
X-708717D01*
X-708050Y-535733D01*
X-707550Y-536200D01*
G01X-696700Y-535500D02*
X-694700D01*
G01X-695700D02*
Y-542500D01*
G01X-696700D02*
X-694700D01*
G01X-690650Y-541567D02*
X-689983Y-542150D01*
X-689233Y-542500D01*
X-688567D01*
X-687900Y-542150D01*
X-687400Y-541567D01*
X-687150Y-540750D01*
X-687317Y-539933D01*
X-687733Y-539233D01*
X-688483Y-538767D01*
X-689483Y-538533D01*
X-690067Y-538067D01*
X-690317Y-537250D01*
X-690150Y-536433D01*
X-689733Y-535850D01*
X-689150Y-535500D01*
X-688567D01*
X-687983Y-535733D01*
X-687483Y-536317D01*
G01X-676967Y-542500D02*
Y-535500D01*
X-674883D01*
X-674217Y-535850D01*
X-673800Y-536317D01*
X-673633Y-537250D01*
X-673800Y-538183D01*
X-674300Y-538767D01*
X-674883Y-539117D01*
X-676967D01*
G01X-674883D02*
X-673633Y-542500D01*
G01X-666833D02*
X-670167D01*
Y-535500D01*
X-666833D01*
G01X-668167Y-538883D02*
X-670167D01*
G01X-659867Y-536083D02*
X-660367Y-535733D01*
X-660950Y-535500D01*
X-661617D01*
X-662367Y-535850D01*
X-662950Y-536433D01*
X-663367Y-537133D01*
X-663700Y-538300D01*
X-663783Y-539350D01*
X-663617Y-540400D01*
X-663367Y-541100D01*
X-662867Y-541800D01*
X-662283Y-542267D01*
X-661700Y-542500D01*
X-661117D01*
X-660533Y-542267D01*
X-660033Y-541917D01*
X-659617Y-541450D01*
G01X-653233Y-542500D02*
X-656567D01*
Y-535500D01*
X-653233D01*
G01X-654567Y-538883D02*
X-656567D01*
G01X-649100Y-535500D02*
X-647100D01*
G01X-648100D02*
Y-542500D01*
G01X-649100D02*
X-647100D01*
G01X-643383Y-535500D02*
X-641300Y-542500D01*
X-639217Y-535500D01*
G01X-632833Y-542500D02*
X-636167D01*
Y-535500D01*
X-632833D01*
G01X-634167Y-538883D02*
X-636167D01*
G01X-629533Y-542500D02*
Y-535500D01*
X-627867D01*
X-627200Y-535850D01*
X-626700Y-536317D01*
X-626283Y-537017D01*
X-625950Y-537833D01*
X-625867Y-539000D01*
X-625950Y-540167D01*
X-626283Y-540983D01*
X-626700Y-541684D01*
X-627200Y-542150D01*
X-627867Y-542500D01*
X-629533D01*
G01X-615100Y-535500D02*
X-613100D01*
G01X-614100D02*
Y-542500D01*
G01X-615100D02*
X-613100D01*
G01X-609217D02*
Y-535500D01*
X-605383Y-542500D01*
Y-535500D01*
G01X-872500Y-520500D02*
Y-527500D01*
G01X-874417Y-520500D02*
X-870583D01*
G01X-867450Y-527500D02*
Y-520500D01*
G01X-863950D02*
Y-527500D01*
G01Y-524000D02*
X-867450D01*
G01X-857233Y-527500D02*
X-860567D01*
Y-520500D01*
X-857233D01*
G01X-858567Y-523883D02*
X-860567D01*
G01X-846967Y-527500D02*
Y-520500D01*
X-844967D01*
X-844300Y-520850D01*
X-843800Y-521667D01*
X-843633Y-522600D01*
X-843800Y-523533D01*
X-844217Y-524233D01*
X-844967Y-524584D01*
X-846967D01*
G01X-840167Y-527500D02*
Y-520500D01*
X-838083D01*
X-837417Y-520850D01*
X-837000Y-521317D01*
X-836833Y-522250D01*
X-837000Y-523183D01*
X-837500Y-523767D01*
X-838083Y-524117D01*
X-840167D01*
G01X-838083D02*
X-836833Y-527500D01*
G01X-831700D02*
X-832367Y-527383D01*
X-832950Y-526917D01*
X-833450Y-526217D01*
X-833783Y-525400D01*
X-833950Y-524467D01*
Y-523533D01*
X-833783Y-522600D01*
X-833450Y-521783D01*
X-832950Y-521083D01*
X-832367Y-520617D01*
X-831700Y-520500D01*
X-831033Y-520617D01*
X-830450Y-521083D01*
X-829950Y-521783D01*
X-829617Y-522600D01*
X-829450Y-523533D01*
Y-524467D01*
X-829617Y-525400D01*
X-829950Y-526217D01*
X-830450Y-526917D01*
X-831033Y-527383D01*
X-831700Y-527500D01*
G01X-826567D02*
Y-520500D01*
X-824567D01*
X-823900Y-520850D01*
X-823400Y-521667D01*
X-823233Y-522600D01*
X-823400Y-523533D01*
X-823817Y-524233D01*
X-824567Y-524584D01*
X-826567D01*
G01X-819767Y-527500D02*
Y-520500D01*
X-817683D01*
X-817017Y-520850D01*
X-816600Y-521317D01*
X-816433Y-522250D01*
X-816600Y-523183D01*
X-817100Y-523767D01*
X-817683Y-524117D01*
X-819767D01*
G01X-817683D02*
X-816433Y-527500D01*
G01X-812300Y-520500D02*
X-810300D01*
G01X-811300D02*
Y-527500D01*
G01X-812300D02*
X-810300D01*
G01X-802833D02*
X-806167D01*
Y-520500D01*
X-802833D01*
G01X-804167Y-523883D02*
X-806167D01*
G01X-797700Y-520500D02*
Y-527500D01*
G01X-799617Y-520500D02*
X-795783D01*
G01X-792983Y-527500D02*
X-790900Y-520500D01*
X-788817Y-527500D01*
G01X-789567Y-525050D02*
X-792233D01*
G01X-785767Y-527500D02*
Y-520500D01*
X-783683D01*
X-783017Y-520850D01*
X-782600Y-521317D01*
X-782433Y-522250D01*
X-782600Y-523183D01*
X-783100Y-523767D01*
X-783683Y-524117D01*
X-785767D01*
G01X-783683D02*
X-782433Y-527500D01*
G01X-777300D02*
Y-524350D01*
X-778967Y-520500D01*
G01X-775633D02*
X-777300Y-524350D01*
G01X-765367Y-527500D02*
Y-520500D01*
X-763367D01*
X-762700Y-520850D01*
X-762200Y-521667D01*
X-762033Y-522600D01*
X-762200Y-523533D01*
X-762617Y-524233D01*
X-763367Y-524584D01*
X-765367D01*
G01X-758567Y-527500D02*
Y-520500D01*
X-756483D01*
X-755817Y-520850D01*
X-755400Y-521317D01*
X-755233Y-522250D01*
X-755400Y-523183D01*
X-755900Y-523767D01*
X-756483Y-524117D01*
X-758567D01*
G01X-756483D02*
X-755233Y-527500D01*
G01X-750100D02*
X-750767Y-527383D01*
X-751350Y-526917D01*
X-751850Y-526217D01*
X-752183Y-525400D01*
X-752350Y-524467D01*
Y-523533D01*
X-752183Y-522600D01*
X-751850Y-521783D01*
X-751350Y-521083D01*
X-750767Y-520617D01*
X-750100Y-520500D01*
X-749433Y-520617D01*
X-748850Y-521083D01*
X-748350Y-521783D01*
X-748017Y-522600D01*
X-747850Y-523533D01*
Y-524467D01*
X-748017Y-525400D01*
X-748350Y-526217D01*
X-748850Y-526917D01*
X-749433Y-527383D01*
X-750100Y-527500D01*
G01X-744967D02*
Y-520500D01*
X-742967D01*
X-742300Y-520850D01*
X-741800Y-521667D01*
X-741633Y-522600D01*
X-741800Y-523533D01*
X-742217Y-524233D01*
X-742967Y-524584D01*
X-744967D01*
G01X-734833Y-527500D02*
X-738167D01*
Y-520500D01*
X-734833D01*
G01X-736167Y-523883D02*
X-738167D01*
G01X-731367Y-527500D02*
Y-520500D01*
X-729283D01*
X-728617Y-520850D01*
X-728200Y-521317D01*
X-728033Y-522250D01*
X-728200Y-523183D01*
X-728700Y-523767D01*
X-729283Y-524117D01*
X-731367D01*
G01X-729283D02*
X-728033Y-527500D01*
G01X-722900Y-520500D02*
Y-527500D01*
G01X-724817Y-520500D02*
X-720983D01*
G01X-716100Y-527500D02*
Y-524350D01*
X-717767Y-520500D01*
G01X-714433D02*
X-716100Y-524350D01*
G01X-702500Y-527500D02*
X-703167Y-527383D01*
X-703750Y-526917D01*
X-704250Y-526217D01*
X-704583Y-525400D01*
X-704750Y-524467D01*
Y-523533D01*
X-704583Y-522600D01*
X-704250Y-521783D01*
X-703750Y-521083D01*
X-703167Y-520617D01*
X-702500Y-520500D01*
X-701833Y-520617D01*
X-701250Y-521083D01*
X-700750Y-521783D01*
X-700417Y-522600D01*
X-700250Y-523533D01*
Y-524467D01*
X-700417Y-525400D01*
X-700750Y-526217D01*
X-701250Y-526917D01*
X-701833Y-527383D01*
X-702500Y-527500D01*
G01X-697283D02*
Y-520500D01*
X-694117D01*
G01X-695283Y-523883D02*
X-697283D01*
G01X-684267Y-527500D02*
Y-520500D01*
X-682100Y-526333D01*
X-679933Y-520500D01*
Y-527500D01*
G01X-676300Y-520500D02*
X-674300D01*
G01X-675300D02*
Y-527500D01*
G01X-676300D02*
X-674300D01*
G01X-666667Y-521083D02*
X-667167Y-520733D01*
X-667750Y-520500D01*
X-668417D01*
X-669167Y-520850D01*
X-669750Y-521433D01*
X-670167Y-522133D01*
X-670500Y-523300D01*
X-670583Y-524350D01*
X-670417Y-525400D01*
X-670167Y-526100D01*
X-669667Y-526800D01*
X-669083Y-527267D01*
X-668500Y-527500D01*
X-667917D01*
X-667333Y-527267D01*
X-666833Y-526917D01*
X-666417Y-526450D01*
G01X-663367Y-527500D02*
Y-520500D01*
X-661283D01*
X-660617Y-520850D01*
X-660200Y-521317D01*
X-660033Y-522250D01*
X-660200Y-523183D01*
X-660700Y-523767D01*
X-661283Y-524117D01*
X-663367D01*
G01X-661283D02*
X-660033Y-527500D01*
G01X-654900D02*
X-655567Y-527383D01*
X-656150Y-526917D01*
X-656650Y-526217D01*
X-656983Y-525400D01*
X-657150Y-524467D01*
Y-523533D01*
X-656983Y-522600D01*
X-656650Y-521783D01*
X-656150Y-521083D01*
X-655567Y-520617D01*
X-654900Y-520500D01*
X-654233Y-520617D01*
X-653650Y-521083D01*
X-653150Y-521783D01*
X-652817Y-522600D01*
X-652650Y-523533D01*
Y-524467D01*
X-652817Y-525400D01*
X-653150Y-526217D01*
X-653650Y-526917D01*
X-654233Y-527383D01*
X-654900Y-527500D01*
G01X-649850Y-526567D02*
X-649183Y-527150D01*
X-648433Y-527500D01*
X-647767D01*
X-647100Y-527150D01*
X-646600Y-526567D01*
X-646350Y-525750D01*
X-646517Y-524933D01*
X-646933Y-524233D01*
X-647683Y-523767D01*
X-648683Y-523533D01*
X-649267Y-523067D01*
X-649517Y-522250D01*
X-649350Y-521433D01*
X-648933Y-520850D01*
X-648350Y-520500D01*
X-647767D01*
X-647183Y-520733D01*
X-646683Y-521317D01*
G01X-641300Y-527500D02*
X-641967Y-527383D01*
X-642550Y-526917D01*
X-643050Y-526217D01*
X-643383Y-525400D01*
X-643550Y-524467D01*
Y-523533D01*
X-643383Y-522600D01*
X-643050Y-521783D01*
X-642550Y-521083D01*
X-641967Y-520617D01*
X-641300Y-520500D01*
X-640633Y-520617D01*
X-640050Y-521083D01*
X-639550Y-521783D01*
X-639217Y-522600D01*
X-639050Y-523533D01*
Y-524467D01*
X-639217Y-525400D01*
X-639550Y-526217D01*
X-640050Y-526917D01*
X-640633Y-527383D01*
X-641300Y-527500D01*
G01X-636083D02*
Y-520500D01*
X-632917D01*
G01X-634083Y-523883D02*
X-636083D01*
G01X-627700Y-520500D02*
Y-527500D01*
G01X-629617Y-520500D02*
X-625783D01*
G01X-872500Y-505500D02*
Y-512500D01*
G01X-874417Y-505500D02*
X-870583D01*
G01X-867450Y-512500D02*
Y-505500D01*
G01X-863950D02*
Y-512500D01*
G01Y-509000D02*
X-867450D01*
G01X-859900Y-505500D02*
X-857900D01*
G01X-858900D02*
Y-512500D01*
G01X-859900D02*
X-857900D01*
G01X-853850Y-511567D02*
X-853183Y-512150D01*
X-852433Y-512500D01*
X-851767D01*
X-851100Y-512150D01*
X-850600Y-511567D01*
X-850350Y-510750D01*
X-850517Y-509933D01*
X-850933Y-509233D01*
X-851683Y-508767D01*
X-852683Y-508533D01*
X-853267Y-508067D01*
X-853517Y-507250D01*
X-853350Y-506433D01*
X-852933Y-505850D01*
X-852350Y-505500D01*
X-851767D01*
X-851183Y-505733D01*
X-850683Y-506317D01*
G01X-840333Y-512500D02*
Y-505500D01*
X-838667D01*
X-838000Y-505850D01*
X-837500Y-506317D01*
X-837083Y-507017D01*
X-836750Y-507833D01*
X-836667Y-509000D01*
X-836750Y-510167D01*
X-837083Y-510983D01*
X-837500Y-511684D01*
X-838000Y-512150D01*
X-838667Y-512500D01*
X-840333D01*
G01X-833367D02*
Y-505500D01*
X-831283D01*
X-830617Y-505850D01*
X-830200Y-506317D01*
X-830033Y-507250D01*
X-830200Y-508183D01*
X-830700Y-508767D01*
X-831283Y-509117D01*
X-833367D01*
G01X-831283D02*
X-830033Y-512500D01*
G01X-826983D02*
X-824900Y-505500D01*
X-822817Y-512500D01*
G01X-823567Y-510050D02*
X-826233D01*
G01X-820600Y-505500D02*
X-819433Y-512500D01*
X-818100Y-505500D01*
X-816767Y-512500D01*
X-815600Y-505500D01*
G01X-812300D02*
X-810300D01*
G01X-811300D02*
Y-512500D01*
G01X-812300D02*
X-810300D01*
G01X-806417D02*
Y-505500D01*
X-802583Y-512500D01*
Y-505500D01*
G01X-797200Y-509000D02*
X-795533D01*
Y-511100D01*
X-796033Y-511800D01*
X-796617Y-512267D01*
X-797450Y-512500D01*
X-798283Y-512267D01*
X-798867Y-511800D01*
X-799367Y-511100D01*
X-799700Y-510283D01*
X-799867Y-509350D01*
Y-508533D01*
X-799700Y-507833D01*
X-799367Y-507017D01*
X-798867Y-506317D01*
X-798367Y-505850D01*
X-797700Y-505500D01*
X-797117D01*
X-796450Y-505733D01*
X-795950Y-506200D01*
G01X-782267Y-506083D02*
X-782767Y-505733D01*
X-783350Y-505500D01*
X-784017D01*
X-784767Y-505850D01*
X-785350Y-506433D01*
X-785767Y-507133D01*
X-786100Y-508300D01*
X-786183Y-509350D01*
X-786017Y-510400D01*
X-785767Y-511100D01*
X-785267Y-511800D01*
X-784683Y-512267D01*
X-784100Y-512500D01*
X-783517D01*
X-782933Y-512267D01*
X-782433Y-511917D01*
X-782017Y-511450D01*
G01X-777300Y-512500D02*
X-777967Y-512383D01*
X-778550Y-511917D01*
X-779050Y-511217D01*
X-779383Y-510400D01*
X-779550Y-509467D01*
Y-508533D01*
X-779383Y-507600D01*
X-779050Y-506783D01*
X-778550Y-506083D01*
X-777967Y-505617D01*
X-777300Y-505500D01*
X-776633Y-505617D01*
X-776050Y-506083D01*
X-775550Y-506783D01*
X-775217Y-507600D01*
X-775050Y-508533D01*
Y-509467D01*
X-775217Y-510400D01*
X-775550Y-511217D01*
X-776050Y-511917D01*
X-776633Y-512383D01*
X-777300Y-512500D01*
G01X-772417D02*
Y-505500D01*
X-768583Y-512500D01*
Y-505500D01*
G01X-763700D02*
Y-512500D01*
G01X-765617Y-505500D02*
X-761783D01*
G01X-758983Y-512500D02*
X-756900Y-505500D01*
X-754817Y-512500D01*
G01X-755567Y-510050D02*
X-758233D01*
G01X-751100Y-505500D02*
X-749100D01*
G01X-750100D02*
Y-512500D01*
G01X-751100D02*
X-749100D01*
G01X-745217D02*
Y-505500D01*
X-741383Y-512500D01*
Y-505500D01*
G01X-738250Y-511567D02*
X-737583Y-512150D01*
X-736833Y-512500D01*
X-736167D01*
X-735500Y-512150D01*
X-735000Y-511567D01*
X-734750Y-510750D01*
X-734917Y-509933D01*
X-735333Y-509233D01*
X-736083Y-508767D01*
X-737083Y-508533D01*
X-737667Y-508067D01*
X-737917Y-507250D01*
X-737750Y-506433D01*
X-737333Y-505850D01*
X-736750Y-505500D01*
X-736167D01*
X-735583Y-505733D01*
X-735083Y-506317D01*
G01X-723900Y-505500D02*
X-721900D01*
G01X-722900D02*
Y-512500D01*
G01X-723900D02*
X-721900D01*
G01X-718017D02*
Y-505500D01*
X-714183Y-512500D01*
Y-505500D01*
G01X-710883Y-512500D02*
Y-505500D01*
X-707717D01*
G01X-708883Y-508883D02*
X-710883D01*
G01X-702500Y-512500D02*
X-703167Y-512383D01*
X-703750Y-511917D01*
X-704250Y-511217D01*
X-704583Y-510400D01*
X-704750Y-509467D01*
Y-508533D01*
X-704583Y-507600D01*
X-704250Y-506783D01*
X-703750Y-506083D01*
X-703167Y-505617D01*
X-702500Y-505500D01*
X-701833Y-505617D01*
X-701250Y-506083D01*
X-700750Y-506783D01*
X-700417Y-507600D01*
X-700250Y-508533D01*
Y-509467D01*
X-700417Y-510400D01*
X-700750Y-511217D01*
X-701250Y-511917D01*
X-701833Y-512383D01*
X-702500Y-512500D01*
G01X-697367D02*
Y-505500D01*
X-695283D01*
X-694617Y-505850D01*
X-694200Y-506317D01*
X-694033Y-507250D01*
X-694200Y-508183D01*
X-694700Y-508767D01*
X-695283Y-509117D01*
X-697367D01*
G01X-695283D02*
X-694033Y-512500D01*
G01X-691067D02*
Y-505500D01*
X-688900Y-511333D01*
X-686733Y-505500D01*
Y-512500D01*
G01X-684183D02*
X-682100Y-505500D01*
X-680017Y-512500D01*
G01X-680767Y-510050D02*
X-683433D01*
G01X-675300Y-505500D02*
Y-512500D01*
G01X-677217Y-505500D02*
X-673383D01*
G01X-669500D02*
X-667500D01*
G01X-668500D02*
Y-512500D01*
G01X-669500D02*
X-667500D01*
G01X-661700D02*
X-662367Y-512383D01*
X-662950Y-511917D01*
X-663450Y-511217D01*
X-663783Y-510400D01*
X-663950Y-509467D01*
Y-508533D01*
X-663783Y-507600D01*
X-663450Y-506783D01*
X-662950Y-506083D01*
X-662367Y-505617D01*
X-661700Y-505500D01*
X-661033Y-505617D01*
X-660450Y-506083D01*
X-659950Y-506783D01*
X-659617Y-507600D01*
X-659450Y-508533D01*
Y-509467D01*
X-659617Y-510400D01*
X-659950Y-511217D01*
X-660450Y-511917D01*
X-661033Y-512383D01*
X-661700Y-512500D01*
G01X-656817D02*
Y-505500D01*
X-652983Y-512500D01*
Y-505500D01*
G01X-643800D02*
X-642633Y-512500D01*
X-641300Y-505500D01*
X-639967Y-512500D01*
X-638800Y-505500D01*
G01X-636250Y-512500D02*
Y-505500D01*
G01X-632750D02*
Y-512500D01*
G01Y-509000D02*
X-636250D01*
G01X-628700Y-505500D02*
X-626700D01*
G01X-627700D02*
Y-512500D01*
G01X-628700D02*
X-626700D01*
G01X-619067Y-506083D02*
X-619567Y-505733D01*
X-620150Y-505500D01*
X-620817D01*
X-621567Y-505850D01*
X-622150Y-506433D01*
X-622567Y-507133D01*
X-622900Y-508300D01*
X-622983Y-509350D01*
X-622817Y-510400D01*
X-622567Y-511100D01*
X-622067Y-511800D01*
X-621483Y-512267D01*
X-620900Y-512500D01*
X-620317D01*
X-619733Y-512267D01*
X-619233Y-511917D01*
X-618817Y-511450D01*
G01X-615850Y-512500D02*
Y-505500D01*
G01X-612350D02*
Y-512500D01*
G01Y-509000D02*
X-615850D01*
G01X-601500Y-505500D02*
X-599500D01*
G01X-600500D02*
Y-512500D01*
G01X-601500D02*
X-599500D01*
G01X-595450Y-511567D02*
X-594783Y-512150D01*
X-594033Y-512500D01*
X-593367D01*
X-592700Y-512150D01*
X-592200Y-511567D01*
X-591950Y-510750D01*
X-592117Y-509933D01*
X-592533Y-509233D01*
X-593283Y-508767D01*
X-594283Y-508533D01*
X-594867Y-508067D01*
X-595117Y-507250D01*
X-594950Y-506433D01*
X-594533Y-505850D01*
X-593950Y-505500D01*
X-593367D01*
X-592783Y-505733D01*
X-592283Y-506317D01*
G01X-858133Y-452500D02*
Y-445500D01*
X-856467D01*
X-855800Y-445850D01*
X-855300Y-446317D01*
X-854883Y-447017D01*
X-854550Y-447833D01*
X-854467Y-449000D01*
X-854550Y-450167D01*
X-854883Y-450983D01*
X-855300Y-451684D01*
X-855800Y-452150D01*
X-856467Y-452500D01*
X-858133D01*
G01X-847833D02*
X-851167D01*
Y-445500D01*
X-847833D01*
G01X-849167Y-448883D02*
X-851167D01*
G01X-844450Y-451567D02*
X-843783Y-452150D01*
X-843033Y-452500D01*
X-842367D01*
X-841700Y-452150D01*
X-841200Y-451567D01*
X-840950Y-450750D01*
X-841117Y-449933D01*
X-841533Y-449233D01*
X-842283Y-448767D01*
X-843283Y-448533D01*
X-843867Y-448067D01*
X-844117Y-447250D01*
X-843950Y-446433D01*
X-843533Y-445850D01*
X-842950Y-445500D01*
X-842367D01*
X-841783Y-445733D01*
X-841283Y-446317D01*
G01X-836900Y-445500D02*
X-834900D01*
G01X-835900D02*
Y-452500D01*
G01X-836900D02*
X-834900D01*
G01X-828600Y-449000D02*
X-826933D01*
Y-451100D01*
X-827433Y-451800D01*
X-828017Y-452267D01*
X-828850Y-452500D01*
X-829683Y-452267D01*
X-830267Y-451800D01*
X-830767Y-451100D01*
X-831100Y-450283D01*
X-831267Y-449350D01*
Y-448533D01*
X-831100Y-447833D01*
X-830767Y-447017D01*
X-830267Y-446317D01*
X-829767Y-445850D01*
X-829100Y-445500D01*
X-828517D01*
X-827850Y-445733D01*
X-827350Y-446200D01*
G01X-824217Y-452500D02*
Y-445500D01*
X-820383Y-452500D01*
Y-445500D01*
G01X-813833Y-452500D02*
X-817167D01*
Y-445500D01*
X-813833D01*
G01X-815167Y-448883D02*
X-817167D01*
G01X-810367Y-452500D02*
Y-445500D01*
X-808283D01*
X-807617Y-445850D01*
X-807200Y-446317D01*
X-807033Y-447250D01*
X-807200Y-448183D01*
X-807700Y-448767D01*
X-808283Y-449117D01*
X-810367D01*
G01X-808283D02*
X-807033Y-452500D01*
G01X-858133D02*
Y-445500D01*
X-856467D01*
X-855800Y-445850D01*
X-855300Y-446317D01*
X-854883Y-447017D01*
X-854550Y-447833D01*
X-854467Y-449000D01*
X-854550Y-450167D01*
X-854883Y-450983D01*
X-855300Y-451684D01*
X-855800Y-452150D01*
X-856467Y-452500D01*
X-858133D01*
G01X-847833D02*
X-851167D01*
Y-445500D01*
X-847833D01*
G01X-849167Y-448883D02*
X-851167D01*
G01X-844450Y-451567D02*
X-843783Y-452150D01*
X-843033Y-452500D01*
X-842367D01*
X-841700Y-452150D01*
X-841200Y-451567D01*
X-840950Y-450750D01*
X-841117Y-449933D01*
X-841533Y-449233D01*
X-842283Y-448767D01*
X-843283Y-448533D01*
X-843867Y-448067D01*
X-844117Y-447250D01*
X-843950Y-446433D01*
X-843533Y-445850D01*
X-842950Y-445500D01*
X-842367D01*
X-841783Y-445733D01*
X-841283Y-446317D01*
G01X-836900Y-445500D02*
X-834900D01*
G01X-835900D02*
Y-452500D01*
G01X-836900D02*
X-834900D01*
G01X-828600Y-449000D02*
X-826933D01*
Y-451100D01*
X-827433Y-451800D01*
X-828017Y-452267D01*
X-828850Y-452500D01*
X-829683Y-452267D01*
X-830267Y-451800D01*
X-830767Y-451100D01*
X-831100Y-450283D01*
X-831267Y-449350D01*
Y-448533D01*
X-831100Y-447833D01*
X-830767Y-447017D01*
X-830267Y-446317D01*
X-829767Y-445850D01*
X-829100Y-445500D01*
X-828517D01*
X-827850Y-445733D01*
X-827350Y-446200D01*
G01X-824217Y-452500D02*
Y-445500D01*
X-820383Y-452500D01*
Y-445500D01*
G01X-813833Y-452500D02*
X-817167D01*
Y-445500D01*
X-813833D01*
G01X-815167Y-448883D02*
X-817167D01*
G01X-810367Y-452500D02*
Y-445500D01*
X-808283D01*
X-807617Y-445850D01*
X-807200Y-446317D01*
X-807033Y-447250D01*
X-807200Y-448183D01*
X-807700Y-448767D01*
X-808283Y-449117D01*
X-810367D01*
G01X-808283D02*
X-807033Y-452500D01*
G01X-642033Y-455000D02*
Y-448000D01*
X-640367D01*
X-639700Y-448350D01*
X-639200Y-448817D01*
X-638783Y-449517D01*
X-638450Y-450333D01*
X-638367Y-451500D01*
X-638450Y-452667D01*
X-638783Y-453483D01*
X-639200Y-454184D01*
X-639700Y-454650D01*
X-640367Y-455000D01*
X-642033D01*
G01X-635483D02*
X-633400Y-448000D01*
X-631317Y-455000D01*
G01X-632067Y-452550D02*
X-634733D01*
G01X-626600Y-448000D02*
Y-455000D01*
G01X-628517Y-448000D02*
X-624683D01*
G01X-618133Y-455000D02*
X-621467D01*
Y-448000D01*
X-618133D01*
G01X-619467Y-451383D02*
X-621467D01*
G54D19*
X-1519000Y-125359D03*
Y-120241D03*
X-1396100Y-136650D03*
Y-131550D03*
X-1356500Y-16041D03*
Y-21159D03*
X-1324500Y-16841D03*
Y-21959D03*
X-1316728Y-85900D03*
Y-80800D03*
X-1317700Y-69059D03*
Y-63941D03*
X-1113328Y-179209D03*
Y-174091D03*
X-1107828D03*
Y-179209D03*
X-1061900Y-38150D03*
X-1063928Y-53400D03*
Y-48300D03*
X-1061900Y-33050D03*
X-1062000Y-9450D03*
Y-14550D03*
X-948500Y-170441D03*
Y-175559D03*
X-649700Y-125359D03*
Y-120241D03*
X-535500Y-127350D03*
Y-122250D03*
X-486421Y-16041D03*
Y-21159D03*
X-448128Y-85800D03*
Y-80700D03*
X-449100Y-63841D03*
Y-68959D03*
X-454421Y-16841D03*
Y-21959D03*
X-243250Y-179209D03*
Y-174091D03*
X-237750D03*
Y-179209D03*
X-190100Y-38450D03*
X-192350Y-52900D03*
Y-47800D03*
X-190100Y-33350D03*
X-190400Y-8750D03*
Y-13850D03*
X-78400Y-171441D03*
Y-176559D03*
G54D37*
X-806854Y-99635D03*
Y-83100D03*
X-785200Y-99635D03*
G54D28*
X-1282480Y-172283D03*
Y-130157D03*
Y-94724D03*
Y-59291D03*
Y-23858D03*
X-1253740Y-184094D03*
X-1225394D03*
X-1207677Y-154567D03*
Y-112441D03*
Y-77008D03*
Y-41575D03*
Y-6142D03*
X-412402Y-172283D03*
Y-130157D03*
Y-94724D03*
Y-59291D03*
Y-23858D03*
X-383661Y-184094D03*
X-355315D03*
X-337598Y-154567D03*
Y-112441D03*
Y-77008D03*
Y-41575D03*
Y-6142D03*
G54D47*
G01X-1020800Y-457700D02*
G02X-1020300Y-458200I0J-500D01*
G01Y-458400D01*
G02X-1020900Y-459000I-600J0D01*
G01X-1021300D01*
G01X-1021800Y-460500D02*
Y-457700D01*
X-1020600D01*
G01X-1018340Y-459100D02*
G03I-2660J0D01*
G01X-1020700D02*
X-1020200Y-460500D01*
G01X-906580Y-119294D02*
X-904820D01*
G01X-906580Y-119694D02*
X-904820D01*
G01X-902880Y-124794D02*
X-901120D01*
G01X-902880Y-124394D02*
X-901120D01*
G01X-906580Y-120094D02*
X-904820D01*
G01X-906480Y-120694D02*
X-904720D01*
G01X-902880Y-123994D02*
X-901120D01*
G01X-906480Y-120194D02*
X-904720D01*
G01X-907860Y-122094D02*
X-906100D01*
G01X-907860Y-122254D02*
X-906100D01*
G01X-907860Y-122414D02*
X-906100D01*
G01X-907860Y-122574D02*
X-906100D01*
G01X-907860Y-122734D02*
X-906100D01*
G01X-907860Y-122894D02*
X-906100D01*
G01X-907860Y-123054D02*
X-906100D01*
G01X-907860Y-123214D02*
X-906100D01*
G01X-907860Y-123374D02*
X-906100D01*
G01X-907860Y-123534D02*
X-906100D01*
G01X-907860Y-123694D02*
X-906100D01*
G01X-907860Y-123854D02*
X-906100D01*
G01X-907860Y-124014D02*
X-906100D01*
G01X-907860Y-124174D02*
X-906100D01*
G01X-907860Y-124334D02*
X-906100D01*
G01X-907860Y-124494D02*
X-906100D01*
G01X-907860Y-124654D02*
X-906100D01*
G01X-907860Y-124814D02*
X-906100D01*
G01X-907860Y-124974D02*
X-906100D01*
G01X-907860Y-125134D02*
X-906100D01*
G01X-907860Y-125294D02*
X-906100D01*
G01X-907860Y-125454D02*
X-906100D01*
G01X-907860Y-125614D02*
X-906100D01*
G01X-907860Y-125774D02*
X-906100D01*
G01X-907860Y-125934D02*
X-906100D01*
G01X-907860Y-126094D02*
X-906100D01*
G01X-907860Y-126254D02*
X-906100D01*
G01X-907860Y-126414D02*
X-906100D01*
G01X-907860Y-126574D02*
X-906100D01*
G01X-907860Y-126734D02*
X-906100D01*
G01X-907860Y-126894D02*
X-906100D01*
G01X-907860Y-127054D02*
X-906100D01*
G01X-907860Y-127214D02*
X-906100D01*
G01X-907860Y-117774D02*
X-904820D01*
G01X-907860Y-117934D02*
X-904820D01*
G01X-907860Y-118094D02*
X-904660D01*
G01X-907860Y-118254D02*
X-904660D01*
G01X-907860Y-118414D02*
X-904500D01*
G01X-907860Y-118574D02*
X-904500D01*
G01X-907860Y-118734D02*
X-906260D01*
G01X-907860Y-118894D02*
X-906260D01*
G01X-907860Y-119054D02*
X-906260D01*
G01X-907860Y-119214D02*
X-906100D01*
G01X-907860Y-119374D02*
X-906100D01*
G01X-907860Y-119534D02*
X-906100D01*
G01X-907860Y-119694D02*
X-906100D01*
G01X-907860Y-119854D02*
X-906100D01*
G01X-907860Y-120014D02*
X-906100D01*
G01X-907860Y-120174D02*
X-906100D01*
G01X-907860Y-120334D02*
X-906100D01*
G01X-907860Y-120494D02*
X-906100D01*
G01X-907860Y-120654D02*
X-906100D01*
G01X-907860Y-120814D02*
X-906100D01*
G01X-907860Y-120974D02*
X-906100D01*
G01X-907860Y-121134D02*
X-906100D01*
G01X-907860Y-121294D02*
X-906100D01*
G01X-907860Y-121454D02*
X-906100D01*
G01X-907860Y-121614D02*
X-906100D01*
G01X-907860Y-121774D02*
X-906100D01*
G01X-907860Y-121934D02*
X-906100D01*
G01X-904820Y-122094D02*
X-903060D01*
G01X-900820D02*
X-899380D01*
G01X-904660Y-122254D02*
X-903060D01*
G01X-900980D02*
X-899380D01*
G01X-904660Y-122414D02*
X-903060D01*
G01X-900980D02*
X-899540D01*
G01X-904500Y-122574D02*
X-902900D01*
G01X-901140D02*
X-899540D01*
G01X-904500Y-122734D02*
X-902900D01*
G01X-901140D02*
X-899540D01*
G01X-904500Y-122894D02*
X-902740D01*
G01X-901140D02*
X-899700D01*
G01X-904340Y-123054D02*
X-902740D01*
G01X-901300D02*
X-899700D01*
G01X-904340Y-123214D02*
X-902740D01*
G01X-901300D02*
X-899860D01*
G01X-904180Y-123374D02*
X-902580D01*
G01X-901460D02*
X-899860D01*
G01X-904180Y-123534D02*
X-902580D01*
G01X-901460D02*
X-899860D01*
G01X-904180Y-123694D02*
X-902420D01*
G01X-901460D02*
X-900020D01*
G01X-904020Y-123854D02*
X-902420D01*
G01X-901620D02*
X-900020D01*
G01X-904020Y-124014D02*
X-902420D01*
G01X-901620D02*
X-900180D01*
G01X-903860Y-124174D02*
X-902260D01*
G01X-901780D02*
X-900180D01*
G01X-903860Y-124334D02*
X-902260D01*
G01X-901780D02*
X-900180D01*
G01X-903860Y-124494D02*
X-902100D01*
G01X-901780D02*
X-900340D01*
G01X-903700Y-124654D02*
X-902100D01*
G01X-901940D02*
X-900340D01*
G01X-903700Y-124814D02*
X-902100D01*
G01X-901940D02*
X-900500D01*
G01X-903540Y-124974D02*
X-900500D01*
G01X-903540Y-125134D02*
X-900660D01*
G01X-903540Y-125294D02*
X-900660D01*
G01X-903380Y-125454D02*
X-900660D01*
G01X-903380Y-125614D02*
X-900820D01*
G01X-903220Y-125774D02*
X-900820D01*
G01X-903220Y-125934D02*
X-900980D01*
G01X-903220Y-126094D02*
X-900980D01*
G01X-903060Y-126254D02*
X-900980D01*
G01X-903060Y-126414D02*
X-901140D01*
G01X-902900Y-126574D02*
X-901140D01*
G01X-902900Y-126734D02*
X-901300D01*
G01X-902740Y-126894D02*
X-901300D01*
G01X-902740Y-127054D02*
X-901300D01*
G01X-902740Y-127214D02*
X-901460D01*
G01X-906100Y-118734D02*
X-904500D01*
G01X-906100Y-118894D02*
X-904340D01*
G01X-905940Y-119054D02*
X-904340D01*
G01X-905940Y-119214D02*
X-904180D01*
G01X-905940Y-119374D02*
X-904180D01*
G01X-905780Y-119534D02*
X-904180D01*
G01X-899860D02*
X-898260D01*
G01X-905780Y-119694D02*
X-904020D01*
G01X-899860D02*
X-898420D01*
G01X-905620Y-119854D02*
X-904020D01*
G01X-900020D02*
X-898420D01*
G01X-905620Y-120014D02*
X-903860D01*
G01X-900020D02*
X-898580D01*
G01X-905620Y-120174D02*
X-903860D01*
G01X-900020D02*
X-898580D01*
G01X-905460Y-120334D02*
X-903860D01*
G01X-900180D02*
X-898580D01*
G01X-905460Y-120494D02*
X-903700D01*
G01X-900180D02*
X-898740D01*
G01X-905300Y-120654D02*
X-903700D01*
G01X-900340D02*
X-898740D01*
G01X-905300Y-120814D02*
X-903540D01*
G01X-900340D02*
X-898900D01*
G01X-905300Y-120974D02*
X-903540D01*
G01X-900500D02*
X-898900D01*
G01X-905140Y-121134D02*
X-903540D01*
G01X-900500D02*
X-898900D01*
G01X-905140Y-121294D02*
X-903380D01*
G01X-900500D02*
X-899060D01*
G01X-904980Y-121454D02*
X-903380D01*
G01X-900660D02*
X-899060D01*
G01X-904980Y-121614D02*
X-903380D01*
G01X-900660D02*
X-899220D01*
G01X-904820Y-121774D02*
X-903220D01*
G01X-900820D02*
X-899220D01*
G01X-904820Y-121934D02*
X-903220D01*
G01X-900820D02*
X-899220D01*
G01X-907860Y-116654D02*
X-905300D01*
G01X-907860Y-116814D02*
X-905140D01*
G01X-907860Y-116974D02*
X-905140D01*
G01X-907860Y-117134D02*
X-905140D01*
G01X-907860Y-117294D02*
X-904980D01*
G01X-907860Y-117454D02*
X-904980D01*
G01X-907860Y-117614D02*
X-904820D01*
G01X-899180Y-119094D02*
X-897420D01*
G01X-899180Y-119494D02*
X-897420D01*
G01X-899180Y-119894D02*
X-897420D01*
G01X-899280Y-120494D02*
X-897520D01*
G01X-899280Y-120894D02*
X-897520D01*
G01X-897940Y-122094D02*
X-896180D01*
G01X-897940Y-122254D02*
X-896180D01*
G01X-897940Y-122414D02*
X-896180D01*
G01X-897940Y-122574D02*
X-896180D01*
G01X-897940Y-122734D02*
X-896180D01*
G01X-897940Y-122894D02*
X-896180D01*
G01X-897940Y-123054D02*
X-896180D01*
G01X-897940Y-123214D02*
X-896180D01*
G01X-897940Y-123374D02*
X-896180D01*
G01X-897940Y-123534D02*
X-896180D01*
G01X-897940Y-123694D02*
X-896180D01*
G01X-897940Y-123854D02*
X-896180D01*
G01X-897940Y-124014D02*
X-896180D01*
G01X-897940Y-124174D02*
X-896180D01*
G01X-897940Y-124334D02*
X-896180D01*
G01X-897940Y-124494D02*
X-896180D01*
G01X-897940Y-124654D02*
X-896180D01*
G01X-897940Y-124814D02*
X-896180D01*
G01X-897940Y-124974D02*
X-896180D01*
G01X-897940Y-125134D02*
X-896180D01*
G01X-897940Y-125294D02*
X-896180D01*
G01X-897940Y-125454D02*
X-896180D01*
G01X-897940Y-125614D02*
X-896180D01*
G01X-897940Y-125774D02*
X-896180D01*
G01X-897940Y-125934D02*
X-896180D01*
G01X-897940Y-126094D02*
X-896180D01*
G01X-897940Y-126254D02*
X-896180D01*
G01X-897940Y-126414D02*
X-896180D01*
G01X-897940Y-126574D02*
X-896180D01*
G01X-897940Y-126734D02*
X-896180D01*
G01X-897940Y-126894D02*
X-896180D01*
G01X-897940Y-127054D02*
X-896180D01*
G01X-897940Y-127214D02*
X-896180D01*
G01X-899060Y-117774D02*
X-896180D01*
G01X-899220Y-117934D02*
X-896180D01*
G01X-899220Y-118094D02*
X-896180D01*
G01X-899380Y-118254D02*
X-896180D01*
G01X-899380Y-118414D02*
X-896180D01*
G01X-899380Y-118574D02*
X-896180D01*
G01X-899540Y-118734D02*
X-898100D01*
G01X-897940D02*
X-896180D01*
G01X-899540Y-118894D02*
X-898100D01*
G01X-897940D02*
X-896180D01*
G01X-899700Y-119054D02*
X-898100D01*
G01X-897940D02*
X-896180D01*
G01X-899700Y-119214D02*
X-898260D01*
G01X-897940D02*
X-896180D01*
G01X-899700Y-119374D02*
X-898260D01*
G01X-897940D02*
X-896180D01*
G01X-897940Y-119534D02*
X-896180D01*
G01X-897940Y-119694D02*
X-896180D01*
G01X-897940Y-119854D02*
X-896180D01*
G01X-897940Y-120014D02*
X-896180D01*
G01X-897940Y-120174D02*
X-896180D01*
G01X-897940Y-120334D02*
X-896180D01*
G01X-897940Y-120494D02*
X-896180D01*
G01X-897940Y-120654D02*
X-896180D01*
G01X-897940Y-120814D02*
X-896180D01*
G01X-897940Y-120974D02*
X-896180D01*
G01X-897940Y-121134D02*
X-896180D01*
G01X-897940Y-121294D02*
X-896180D01*
G01X-897940Y-121454D02*
X-896180D01*
G01X-897940Y-121614D02*
X-896180D01*
G01X-897940Y-121774D02*
X-896180D01*
G01X-897940Y-121934D02*
X-896180D01*
G01X-893780Y-122094D02*
X-892020D01*
G01X-890100D02*
X-888180D01*
G01X-893780Y-122254D02*
X-892020D01*
G01X-890100D02*
X-888180D01*
G01X-893780Y-122414D02*
X-892020D01*
G01X-890100D02*
X-888340D01*
G01X-893780Y-122574D02*
X-892020D01*
G01X-890100D02*
X-888340D01*
G01X-893780Y-122734D02*
X-892020D01*
G01X-890260D02*
X-888340D01*
G01X-893780Y-122894D02*
X-892020D01*
G01X-890260D02*
X-888500D01*
G01X-893780Y-123054D02*
X-892020D01*
G01X-890260D02*
X-888500D01*
G01X-893780Y-123214D02*
X-892020D01*
G01X-890260D02*
X-888500D01*
G01X-893780Y-123374D02*
X-892020D01*
G01X-890260D02*
X-888500D01*
G01X-893780Y-123534D02*
X-892020D01*
G01X-890260D02*
X-888500D01*
G01X-893780Y-123694D02*
X-892020D01*
G01X-890260D02*
X-888500D01*
G01X-893780Y-123854D02*
X-892020D01*
G01X-890260D02*
X-888500D01*
G01X-893780Y-124014D02*
X-892020D01*
G01X-890260D02*
X-888500D01*
G01X-893780Y-124174D02*
X-892020D01*
G01X-890260D02*
X-888500D01*
G01X-893780Y-124334D02*
X-892020D01*
G01X-890260D02*
X-888340D01*
G01X-893780Y-124494D02*
X-892020D01*
G01X-890100D02*
X-888340D01*
G01X-893780Y-124654D02*
X-892020D01*
G01X-890100D02*
X-888340D01*
G01X-893780Y-124814D02*
X-892020D01*
G01X-890100D02*
X-888180D01*
G01X-893780Y-124974D02*
X-892020D01*
G01X-890100D02*
X-888180D01*
G01X-893780Y-125134D02*
X-892020D01*
G01X-889940D02*
X-888020D01*
G01X-893780Y-125294D02*
X-892020D01*
G01X-889940D02*
X-887860D01*
G01X-893780Y-125454D02*
X-892020D01*
G01X-889940D02*
X-887700D01*
G01X-893780Y-125614D02*
X-892020D01*
G01X-889780D02*
X-887540D01*
G01X-893780Y-125774D02*
X-892020D01*
G01X-889620D02*
X-887220D01*
G01X-893780Y-125934D02*
X-892020D01*
G01X-889620D02*
X-886740D01*
G01X-893780Y-126094D02*
X-892020D01*
G01X-889460D02*
X-884340D01*
G01X-893780Y-126254D02*
X-892020D01*
G01X-889300D02*
X-884340D01*
G01X-893780Y-126414D02*
X-892020D01*
G01X-889140D02*
X-884340D01*
G01X-893780Y-126574D02*
X-892020D01*
G01X-888980D02*
X-884340D01*
G01X-893780Y-126734D02*
X-892020D01*
G01X-888820D02*
X-884340D01*
G01X-893780Y-126894D02*
X-892020D01*
G01X-888500D02*
X-884340D01*
G01X-893780Y-127054D02*
X-892020D01*
G01X-888340D02*
X-884500D01*
G01X-893780Y-127214D02*
X-892020D01*
G01X-887860D02*
X-884980D01*
G01X-893620Y-117774D02*
X-892180D01*
G01X-893300Y-117934D02*
X-892500D01*
G01X-893780Y-119694D02*
X-892020D01*
G01X-887700D02*
X-884660D01*
G01X-893780Y-119854D02*
X-892020D01*
G01X-888020D02*
X-884340D01*
G01X-893780Y-120014D02*
X-892020D01*
G01X-888340D02*
X-884340D01*
G01X-893780Y-120174D02*
X-892020D01*
G01X-888660D02*
X-884340D01*
G01X-893780Y-120334D02*
X-892020D01*
G01X-888820D02*
X-884340D01*
G01X-893780Y-120494D02*
X-892020D01*
G01X-888980D02*
X-884340D01*
G01X-893780Y-120654D02*
X-892020D01*
G01X-889140D02*
X-884340D01*
G01X-893780Y-120814D02*
X-892020D01*
G01X-889300D02*
X-884340D01*
G01X-893780Y-120974D02*
X-892020D01*
G01X-889460D02*
X-886740D01*
G01X-893780Y-121134D02*
X-892020D01*
G01X-889620D02*
X-887060D01*
G01X-893780Y-121294D02*
X-892020D01*
G01X-889620D02*
X-887380D01*
G01X-893780Y-121454D02*
X-892020D01*
G01X-889780D02*
X-887540D01*
G01X-893780Y-121614D02*
X-892020D01*
G01X-889780D02*
X-887700D01*
G01X-893780Y-121774D02*
X-892020D01*
G01X-889940D02*
X-887860D01*
G01X-893780Y-121934D02*
X-892020D01*
G01X-889940D02*
X-888020D01*
G01X-884660Y-125614D02*
X-884340D01*
G01X-884980Y-125774D02*
X-884340D01*
G01X-885300Y-125934D02*
X-884340D01*
G01X-887380Y-127374D02*
X-885620D01*
G01X-887060Y-119534D02*
X-885300D01*
G01Y-120974D02*
X-884340D01*
G01X-884820Y-121134D02*
X-884340D01*
G01X-884660Y-121294D02*
X-884340D01*
G01X-898740Y-116654D02*
X-896180D01*
G01X-898740Y-116814D02*
X-896180D01*
G01X-898740Y-116974D02*
X-896180D01*
G01X-898900Y-117134D02*
X-896180D01*
G01X-898900Y-117294D02*
X-896180D01*
G01X-899060Y-117454D02*
X-896180D01*
G01X-899060Y-117614D02*
X-896180D01*
G01X-893300Y-116174D02*
X-892500D01*
G01X-893620Y-116334D02*
X-892180D01*
G01X-893780Y-116494D02*
X-892020D01*
G01X-893780Y-116654D02*
X-892020D01*
G01X-893940Y-116814D02*
X-891860D01*
G01X-893940Y-116974D02*
X-891860D01*
G01X-893940Y-117134D02*
X-891860D01*
G01X-893940Y-117294D02*
X-891860D01*
G01X-893780Y-117454D02*
X-892020D01*
G01X-893780Y-117614D02*
X-892020D01*
G01X-882580Y-122094D02*
X-880500D01*
G01X-882580Y-122254D02*
X-880500D01*
G01X-882580Y-122414D02*
X-880660D01*
G01X-882580Y-122574D02*
X-880660D01*
G01X-882580Y-122734D02*
X-880660D01*
G01X-882580Y-122894D02*
X-880820D01*
G01X-882580Y-123054D02*
X-880820D01*
G01X-882580Y-123214D02*
X-880820D01*
G01X-882580Y-123374D02*
X-880820D01*
G01X-882580Y-123534D02*
X-880820D01*
G01X-882580Y-123694D02*
X-880820D01*
G01X-882580Y-123854D02*
X-880820D01*
G01X-882580Y-124014D02*
X-880820D01*
G01X-882580Y-124174D02*
X-880820D01*
G01X-882580Y-124334D02*
X-880820D01*
G01X-882580Y-124494D02*
X-880820D01*
G01X-882580Y-124654D02*
X-880820D01*
G01X-882580Y-124814D02*
X-880820D01*
G01X-882580Y-124974D02*
X-880820D01*
G01X-882580Y-125134D02*
X-880820D01*
G01X-882580Y-125294D02*
X-880820D01*
G01X-882580Y-125454D02*
X-880820D01*
G01X-882580Y-125614D02*
X-880820D01*
G01X-882580Y-125774D02*
X-880820D01*
G01X-882580Y-125934D02*
X-880820D01*
G01X-882580Y-126094D02*
X-880820D01*
G01X-882580Y-126254D02*
X-880820D01*
G01X-882580Y-126414D02*
X-880820D01*
G01X-882580Y-126574D02*
X-880820D01*
G01X-882580Y-126734D02*
X-880820D01*
G01X-882580Y-126894D02*
X-880820D01*
G01X-882580Y-127054D02*
X-880820D01*
G01X-882580Y-127214D02*
X-880820D01*
G01X-879220Y-119534D02*
X-878260D01*
G01X-882580Y-119694D02*
X-880820D01*
G01X-879700D02*
X-878100D01*
G01X-882580Y-119854D02*
X-880820D01*
G01X-879860D02*
X-878100D01*
G01X-882580Y-120014D02*
X-880820D01*
G01X-880020D02*
X-878100D01*
G01X-882580Y-120174D02*
X-880820D01*
G01X-880180D02*
X-878100D01*
G01X-882580Y-120334D02*
X-880820D01*
G01X-880340D02*
X-878100D01*
G01X-882580Y-120494D02*
X-880820D01*
G01X-880500D02*
X-878100D01*
G01X-882580Y-120654D02*
X-880820D01*
G01X-880500D02*
X-878100D01*
G01X-882580Y-120814D02*
X-880820D01*
G01X-880660D02*
X-878100D01*
G01X-882580Y-120974D02*
X-880820D01*
G01X-880660D02*
X-878100D01*
G01X-882580Y-121134D02*
X-879540D01*
G01X-878420D02*
X-878100D01*
G01X-882580Y-121294D02*
X-879860D01*
G01X-882580Y-121454D02*
X-880020D01*
G01X-882580Y-121614D02*
X-880180D01*
G01X-882580Y-121774D02*
X-880340D01*
G01X-882580Y-121934D02*
X-880340D01*
G01X-877140Y-122094D02*
X-875220D01*
G01X-871380D02*
X-869620D01*
G01X-877140Y-122254D02*
X-875380D01*
G01X-871380D02*
X-869620D01*
G01X-877140Y-122414D02*
X-875380D01*
G01X-871380D02*
X-869460D01*
G01X-877140Y-122574D02*
X-875380D01*
G01X-871380D02*
X-869460D01*
G01X-877300Y-122734D02*
X-875540D01*
G01X-871220D02*
X-869460D01*
G01X-877300Y-122894D02*
X-875540D01*
G01X-871220D02*
X-869460D01*
G01X-877300Y-123054D02*
X-875540D01*
G01X-871220D02*
X-869460D01*
G01X-877300Y-123214D02*
X-875540D01*
G01X-871220D02*
X-869460D01*
G01X-877300Y-123374D02*
X-875540D01*
G01X-871220D02*
X-869460D01*
G01X-877300Y-123534D02*
X-875540D01*
G01X-871220D02*
X-869460D01*
G01X-877300Y-123694D02*
X-875540D01*
G01X-871220D02*
X-869460D01*
G01X-877300Y-123854D02*
X-875540D01*
G01X-871220D02*
X-869460D01*
G01X-877300Y-124014D02*
X-875540D01*
G01X-871220D02*
X-869460D01*
G01X-877300Y-124174D02*
X-875540D01*
G01X-871220D02*
X-869460D01*
G01X-877300Y-124334D02*
X-875380D01*
G01X-871220D02*
X-869460D01*
G01X-877140Y-124494D02*
X-875380D01*
G01X-871380D02*
X-869620D01*
G01X-877140Y-124654D02*
X-875380D01*
G01X-871380D02*
X-869620D01*
G01X-877140Y-124814D02*
X-875220D01*
G01X-871380D02*
X-869620D01*
G01X-877140Y-124974D02*
X-875220D01*
G01X-871540D02*
X-869620D01*
G01X-876980Y-125134D02*
X-875060D01*
G01X-871540D02*
X-869780D01*
G01X-876980Y-125294D02*
X-874900D01*
G01X-871700D02*
X-869780D01*
G01X-876820Y-125454D02*
X-874900D01*
G01X-871860D02*
X-869940D01*
G01X-876820Y-125614D02*
X-874580D01*
G01X-872020D02*
X-869940D01*
G01X-876660Y-125774D02*
X-874420D01*
G01X-872340D02*
X-870100D01*
G01X-876660Y-125934D02*
X-873940D01*
G01X-872660D02*
X-870100D01*
G01X-876500Y-126094D02*
X-870260D01*
G01X-876340Y-126254D02*
X-870420D01*
G01X-876180Y-126414D02*
X-870580D01*
G01X-876020Y-126574D02*
X-870740D01*
G01X-875860Y-126734D02*
X-870900D01*
G01X-875540Y-126894D02*
X-871220D01*
G01X-875380Y-127054D02*
X-871540D01*
G01X-874900Y-127214D02*
X-871860D01*
G01X-874260Y-127374D02*
X-872500D01*
G01X-874100Y-119534D02*
X-872340D01*
G01X-874740Y-119694D02*
X-871700D01*
G01X-875220Y-119854D02*
X-871380D01*
G01X-875540Y-120014D02*
X-871060D01*
G01X-875700Y-120174D02*
X-870900D01*
G01X-876020Y-120334D02*
X-870580D01*
G01X-876180Y-120494D02*
X-870420D01*
G01X-876340Y-120654D02*
X-870260D01*
G01X-876500Y-120814D02*
X-870260D01*
G01X-876500Y-120974D02*
X-873940D01*
G01X-872660D02*
X-870100D01*
G01X-876660Y-121134D02*
X-874420D01*
G01X-872340D02*
X-869940D01*
G01X-876820Y-121294D02*
X-874580D01*
G01X-872020D02*
X-869940D01*
G01X-876820Y-121454D02*
X-874900D01*
G01X-871860D02*
X-869780D01*
G01X-876980Y-121614D02*
X-874900D01*
G01X-871700D02*
X-869780D01*
G01X-876980Y-121774D02*
X-875060D01*
G01X-871540D02*
X-869620D01*
G01X-876980Y-121934D02*
X-875220D01*
G01X-871540D02*
X-869620D01*
G01X-852820Y-120654D02*
X-847520D01*
G01X-852820Y-120814D02*
X-847520D01*
G01X-852820Y-119854D02*
X-847520D01*
G01X-852820Y-120974D02*
X-847520D01*
G01X-852820Y-119694D02*
X-847520D01*
G01X-868180Y-122094D02*
X-866260D01*
G01X-868020Y-122254D02*
X-866260D01*
G01X-868020Y-122414D02*
X-865940D01*
G01X-868020Y-122574D02*
X-865620D01*
G01X-867860Y-122734D02*
X-865140D01*
G01X-867860Y-122894D02*
X-864820D01*
G01X-867700Y-123054D02*
X-864340D01*
G01X-867540Y-123214D02*
X-864020D01*
G01X-868180Y-125454D02*
X-867860D01*
G01X-868180Y-125614D02*
X-867540D01*
G01X-868180Y-125774D02*
X-867220D01*
G01X-868180Y-125934D02*
X-866740D01*
G01X-868180Y-126094D02*
X-863060D01*
G01X-868180Y-126254D02*
X-863060D01*
G01X-868180Y-126414D02*
X-863220D01*
G01X-868180Y-126574D02*
X-863380D01*
G01X-868180Y-126734D02*
X-863540D01*
G01X-868180Y-126894D02*
X-863700D01*
G01X-868020Y-127054D02*
X-864020D01*
G01X-867540Y-127214D02*
X-864340D01*
G01X-867540Y-120334D02*
X-863220D01*
G01X-867700Y-120494D02*
X-863220D01*
G01X-867860Y-120654D02*
X-863220D01*
G01X-867860Y-120814D02*
X-863220D01*
G01X-868020Y-120974D02*
X-865780D01*
G01X-868020Y-121134D02*
X-866100D01*
G01X-868180Y-121294D02*
X-866260D01*
G01X-868180Y-121454D02*
X-866420D01*
G01X-868180Y-121614D02*
X-866420D01*
G01X-868180Y-121774D02*
X-866420D01*
G01X-868180Y-121934D02*
X-866420D01*
G01X-861460Y-122094D02*
X-859540D01*
G01X-861460Y-122254D02*
X-859700D01*
G01X-861460Y-122414D02*
X-859700D01*
G01X-861460Y-122574D02*
X-859700D01*
G01X-861620Y-122734D02*
X-859860D01*
G01X-861620Y-122894D02*
X-859860D01*
G01X-861620Y-123054D02*
X-859860D01*
G01X-861620Y-123214D02*
X-859860D01*
G01X-867380Y-123374D02*
X-863860D01*
G01X-861620D02*
X-859860D01*
G01X-867060Y-123534D02*
X-863540D01*
G01X-861620D02*
X-859860D01*
G01X-866740Y-123694D02*
X-863380D01*
G01X-861620D02*
X-859860D01*
G01X-866420Y-123854D02*
X-863220D01*
G01X-861620D02*
X-859860D01*
G01X-866100Y-124014D02*
X-863060D01*
G01X-861620D02*
X-859860D01*
G01X-865620Y-124174D02*
X-863060D01*
G01X-861620D02*
X-859860D01*
G01X-865140Y-124334D02*
X-862900D01*
G01X-861620D02*
X-859700D01*
G01X-864980Y-124494D02*
X-862900D01*
G01X-861460D02*
X-859700D01*
G01X-864660Y-124654D02*
X-862740D01*
G01X-861460D02*
X-859700D01*
G01X-864660Y-124814D02*
X-862740D01*
G01X-861460D02*
X-859540D01*
G01X-864500Y-124974D02*
X-862740D01*
G01X-861460D02*
X-859540D01*
G01X-864500Y-125134D02*
X-862740D01*
G01X-861300D02*
X-859380D01*
G01X-864500Y-125294D02*
X-862740D01*
G01X-861300D02*
X-859220D01*
G01X-864500Y-125454D02*
X-862740D01*
G01X-861140D02*
X-859220D01*
G01X-864660Y-125614D02*
X-862740D01*
G01X-861140D02*
X-858900D01*
G01X-864820Y-125774D02*
X-862900D01*
G01X-860980D02*
X-858740D01*
G01X-865140Y-125934D02*
X-862900D01*
G01X-860980D02*
X-858260D01*
G01X-860820Y-126094D02*
X-854580D01*
G01X-860660Y-126254D02*
X-854740D01*
G01X-860500Y-126414D02*
X-854900D01*
G01X-860340Y-126574D02*
X-855060D01*
G01X-860180Y-126734D02*
X-855220D01*
G01X-859860Y-126894D02*
X-855540D01*
G01X-859700Y-127054D02*
X-855860D01*
G01X-859220Y-127214D02*
X-856180D01*
G01X-866900Y-127374D02*
X-865140D01*
G01X-858580D02*
X-856820D01*
G01X-865940Y-119534D02*
X-864020D01*
G01X-858420D02*
X-856660D01*
G01X-866420Y-119694D02*
X-863380D01*
G01X-859060D02*
X-856020D01*
G01X-866900Y-119854D02*
X-863220D01*
G01X-859540D02*
X-855700D01*
G01X-867220Y-120014D02*
X-863220D01*
G01X-859860D02*
X-855380D01*
G01X-867380Y-120174D02*
X-863220D01*
G01X-860020D02*
X-855220D01*
G01X-860340Y-120334D02*
X-854900D01*
G01X-860500Y-120494D02*
X-854740D01*
G01X-860660Y-120654D02*
X-854580D01*
G01X-860820Y-120814D02*
X-854580D01*
G01X-864180Y-120974D02*
X-863220D01*
G01X-860820D02*
X-858260D01*
G01X-863700Y-121134D02*
X-863220D01*
G01X-860980D02*
X-858740D01*
G01X-861140Y-121294D02*
X-858900D01*
G01X-861140Y-121454D02*
X-859220D01*
G01X-861300Y-121614D02*
X-859220D01*
G01X-861300Y-121774D02*
X-859380D01*
G01X-861300Y-121934D02*
X-859540D01*
G01X-855700Y-122094D02*
X-853940D01*
G01X-855700Y-122254D02*
X-853940D01*
G01X-855700Y-122414D02*
X-853780D01*
G01X-855700Y-122574D02*
X-853780D01*
G01X-855540Y-122734D02*
X-853780D01*
G01X-855540Y-122894D02*
X-853780D01*
G01X-855540Y-123054D02*
X-853780D01*
G01X-855540Y-123214D02*
X-853780D01*
G01X-855540Y-123374D02*
X-853780D01*
G01X-855540Y-123534D02*
X-853780D01*
G01X-855540Y-123694D02*
X-853780D01*
G01X-855540Y-123854D02*
X-853780D01*
G01X-855540Y-124014D02*
X-853780D01*
G01X-855540Y-124174D02*
X-853780D01*
G01X-855540Y-124334D02*
X-853780D01*
G01X-855700Y-124494D02*
X-853940D01*
G01X-855700Y-124654D02*
X-853940D01*
G01X-855700Y-124814D02*
X-853940D01*
G01X-855860Y-124974D02*
X-853940D01*
G01X-855860Y-125134D02*
X-854100D01*
G01X-856020Y-125294D02*
X-854100D01*
G01X-856180Y-125454D02*
X-854260D01*
G01X-856340Y-125614D02*
X-854260D01*
G01X-856660Y-125774D02*
X-854420D01*
G01X-856980Y-125934D02*
X-854420D01*
G01X-852820Y-120014D02*
X-848020D01*
G01X-852820Y-120174D02*
X-848020D01*
G01X-852820Y-120334D02*
X-848020D01*
G01X-852820Y-120494D02*
X-848020D01*
G01X-856980Y-120974D02*
X-854420D01*
G01X-856660Y-121134D02*
X-854260D01*
G01X-856340Y-121294D02*
X-854260D01*
G01X-856180Y-121454D02*
X-854100D01*
G01X-856020Y-121614D02*
X-854100D01*
G01X-855860Y-121774D02*
X-853940D01*
G01X-855860Y-121934D02*
X-853940D01*
G01X-848040Y-120014D02*
X-842740D01*
G01X-848040Y-120334D02*
X-842740D01*
G01X-848040Y-120494D02*
X-842740D01*
G01X-851380Y-122094D02*
X-849780D01*
G01X-851380Y-122254D02*
X-849780D01*
G01X-851380Y-122414D02*
X-849780D01*
G01X-851380Y-122574D02*
X-849780D01*
G01X-851380Y-122734D02*
X-849780D01*
G01X-851380Y-122894D02*
X-849780D01*
G01X-851380Y-123054D02*
X-849780D01*
G01X-851380Y-123214D02*
X-849780D01*
G01X-851380Y-123374D02*
X-849780D01*
G01X-851380Y-123534D02*
X-849780D01*
G01X-851380Y-123694D02*
X-849780D01*
G01X-851380Y-123854D02*
X-849780D01*
G01X-851380Y-124014D02*
X-849780D01*
G01X-851380Y-124174D02*
X-849780D01*
G01X-851380Y-124334D02*
X-849780D01*
G01X-851380Y-124494D02*
X-849780D01*
G01X-851380Y-124654D02*
X-849780D01*
G01X-851380Y-124814D02*
X-849780D01*
G01X-851380Y-124974D02*
X-849780D01*
G01X-851380Y-125134D02*
X-849780D01*
G01X-851380Y-125294D02*
X-849780D01*
G01X-851380Y-125454D02*
X-849780D01*
G01X-851380Y-125614D02*
X-849780D01*
G01X-851380Y-125774D02*
X-849780D01*
G01X-851380Y-125934D02*
X-849780D01*
G01X-851380Y-126094D02*
X-849780D01*
G01X-851380Y-126254D02*
X-849780D01*
G01X-851380Y-126414D02*
X-849780D01*
G01X-851380Y-126574D02*
X-849780D01*
G01X-851380Y-126734D02*
X-849780D01*
G01X-851380Y-126894D02*
X-849780D01*
G01X-851380Y-127054D02*
X-849780D01*
G01X-851380Y-127214D02*
X-849780D01*
G01X-851380Y-117774D02*
X-849620D01*
G01X-851380Y-117934D02*
X-849620D01*
G01X-851380Y-118094D02*
X-849620D01*
G01X-851380Y-118254D02*
X-849780D01*
G01X-851380Y-118414D02*
X-849780D01*
G01X-851380Y-118574D02*
X-849780D01*
G01X-851380Y-118734D02*
X-849780D01*
G01X-851380Y-118894D02*
X-849780D01*
G01X-851380Y-119054D02*
X-849780D01*
G01X-851380Y-119214D02*
X-849780D01*
G01X-851380Y-119374D02*
X-849780D01*
G01X-851380Y-119534D02*
X-849780D01*
G01X-847540Y-119694D02*
X-842740D01*
G01X-847540Y-119854D02*
X-842740D01*
G01X-847540Y-120174D02*
X-842740D01*
G01X-847540Y-120654D02*
X-842740D01*
G01X-847540Y-120814D02*
X-842740D01*
G01X-847540Y-120974D02*
X-842740D01*
G01X-851380Y-121134D02*
X-849780D01*
G01X-851380Y-121294D02*
X-849780D01*
G01X-851380Y-121454D02*
X-849780D01*
G01X-851380Y-121614D02*
X-849780D01*
G01X-851380Y-121774D02*
X-849780D01*
G01X-851380Y-121934D02*
X-849780D01*
G01X-846260Y-122094D02*
X-844500D01*
G01X-846260Y-122254D02*
X-844500D01*
G01X-846260Y-122414D02*
X-844500D01*
G01X-846260Y-122574D02*
X-844500D01*
G01X-846260Y-122734D02*
X-844500D01*
G01X-846260Y-122894D02*
X-844500D01*
G01X-846260Y-123054D02*
X-844500D01*
G01X-846260Y-123214D02*
X-844500D01*
G01X-846260Y-123374D02*
X-844500D01*
G01X-846260Y-123534D02*
X-844500D01*
G01X-846260Y-123694D02*
X-844500D01*
G01X-846260Y-123854D02*
X-844500D01*
G01X-846260Y-124014D02*
X-844500D01*
G01X-846260Y-124174D02*
X-844500D01*
G01X-846260Y-124334D02*
X-844500D01*
G01X-846260Y-124494D02*
X-844500D01*
G01X-846260Y-124654D02*
X-844500D01*
G01X-846260Y-124814D02*
X-844500D01*
G01X-846260Y-124974D02*
X-844500D01*
G01X-846260Y-125134D02*
X-844500D01*
G01X-846260Y-125294D02*
X-844500D01*
G01X-846260Y-125454D02*
X-844340D01*
G01X-846260Y-125614D02*
X-844340D01*
G01X-846260Y-125774D02*
X-844180D01*
G01X-846100Y-125934D02*
X-844020D01*
G01X-843060D02*
X-842740D01*
G01X-846100Y-126094D02*
X-842740D01*
G01X-846100Y-126254D02*
X-842740D01*
G01X-845940Y-126414D02*
X-842740D01*
G01X-845940Y-126574D02*
X-842740D01*
G01X-845780Y-126734D02*
X-842740D01*
G01X-845620Y-126894D02*
X-842740D01*
G01X-845460Y-127054D02*
X-842740D01*
G01X-845300Y-127214D02*
X-842740D01*
G01X-844820Y-127374D02*
X-843220D01*
G01X-845940Y-117774D02*
X-844500D01*
G01X-846260Y-117934D02*
X-844500D01*
G01X-846260Y-118094D02*
X-844500D01*
G01X-846260Y-118254D02*
X-844500D01*
G01X-846260Y-118414D02*
X-844500D01*
G01X-846260Y-118574D02*
X-844500D01*
G01X-846260Y-118734D02*
X-844500D01*
G01X-846260Y-118894D02*
X-844500D01*
G01X-846260Y-119054D02*
X-844500D01*
G01X-846260Y-119214D02*
X-844500D01*
G01X-846260Y-119374D02*
X-844500D01*
G01X-846260Y-119534D02*
X-844500D01*
G01X-846260Y-121134D02*
X-844500D01*
G01X-846260Y-121294D02*
X-844500D01*
G01X-846260Y-121454D02*
X-844500D01*
G01X-846260Y-121614D02*
X-844500D01*
G01X-846260Y-121774D02*
X-844500D01*
G01X-846260Y-121934D02*
X-844500D01*
G01X-849460Y-115854D02*
X-847860D01*
G01X-849940Y-116014D02*
X-847700D01*
G01X-850260Y-116174D02*
X-847700D01*
G01X-850420Y-116334D02*
X-847700D01*
G01X-850740Y-116494D02*
X-847700D01*
G01X-850900Y-116654D02*
X-847700D01*
G01X-850900Y-116814D02*
X-847700D01*
G01X-851060Y-116974D02*
X-847700D01*
G01X-851220Y-117134D02*
X-847700D01*
G01X-851220Y-117294D02*
X-848980D01*
G01X-847860D02*
X-847700D01*
G01X-851380Y-117454D02*
X-849300D01*
G01X-851380Y-117614D02*
X-849460D01*
G01X-844820Y-117454D02*
X-844500D01*
G01X-845300Y-117614D02*
X-844500D01*
G54D38*
G01X-1184000Y-502500D02*
Y-512500D01*
G01X-1186683Y-502500D02*
X-1181317D01*
G01X-1176833Y-512500D02*
Y-502500D01*
X-1173917D01*
X-1172983Y-503000D01*
X-1172400Y-503667D01*
X-1172167Y-505000D01*
X-1172400Y-506333D01*
X-1173100Y-507167D01*
X-1173917Y-507667D01*
X-1176833D01*
G01X-1173917D02*
X-1172167Y-512500D01*
G01X-1167917D02*
X-1165000Y-502500D01*
X-1162083Y-512500D01*
G01X-1163133Y-509000D02*
X-1166867D01*
G01X-1155500Y-512500D02*
Y-508000D01*
X-1157833Y-502500D01*
G01X-1153167D02*
X-1155500Y-508000D01*
G01X-1135567Y-507167D02*
X-1135100Y-506667D01*
X-1134750Y-505834D01*
X-1134517Y-504667D01*
X-1134750Y-503667D01*
X-1135217Y-503000D01*
X-1136033Y-502500D01*
X-1139183D01*
Y-512500D01*
X-1135333D01*
X-1134517Y-511833D01*
X-1134050Y-510833D01*
X-1133817Y-509667D01*
X-1134050Y-508500D01*
X-1134750Y-507500D01*
X-1135567Y-507167D01*
X-1139183D01*
G01X-1129917Y-512500D02*
X-1127000Y-502500D01*
X-1124083Y-512500D01*
G01X-1125133Y-509000D02*
X-1128867D01*
G01X-1114933Y-503333D02*
X-1115633Y-502833D01*
X-1116450Y-502500D01*
X-1117383D01*
X-1118433Y-503000D01*
X-1119250Y-503833D01*
X-1119833Y-504833D01*
X-1120300Y-506500D01*
X-1120417Y-508000D01*
X-1120183Y-509500D01*
X-1119833Y-510500D01*
X-1119133Y-511500D01*
X-1118317Y-512167D01*
X-1117500Y-512500D01*
X-1116683D01*
X-1115867Y-512167D01*
X-1115167Y-511667D01*
X-1114583Y-511000D01*
G01X-1110567Y-512500D02*
Y-502500D01*
G01X-1106133D02*
X-1110567Y-508667D01*
G01X-1105433Y-512500D02*
X-1108583Y-505834D01*
G01X-1100833Y-512500D02*
Y-502500D01*
X-1098033D01*
X-1097100Y-503000D01*
X-1096400Y-504167D01*
X-1096167Y-505500D01*
X-1096400Y-506833D01*
X-1096983Y-507833D01*
X-1098033Y-508334D01*
X-1100833D01*
G01X-1091333Y-502500D02*
Y-512500D01*
X-1086667D01*
G01X-1082417D02*
X-1079500Y-502500D01*
X-1076583Y-512500D01*
G01X-1077633Y-509000D02*
X-1081367D01*
G01X-1072683Y-512500D02*
Y-502500D01*
X-1067317Y-512500D01*
Y-502500D01*
G01X-1058167Y-512500D02*
X-1062833D01*
Y-502500D01*
X-1058167D01*
G01X-1060033Y-507333D02*
X-1062833D01*
G01X-1043717Y-512500D02*
Y-502500D01*
X-1039283D01*
G01X-1040917Y-507333D02*
X-1043717D01*
G01X-1034917Y-512500D02*
X-1032000Y-502500D01*
X-1029083Y-512500D01*
G01X-1030133Y-509000D02*
X-1033867D01*
G01X-1021567Y-507167D02*
X-1021100Y-506667D01*
X-1020750Y-505834D01*
X-1020517Y-504667D01*
X-1020750Y-503667D01*
X-1021217Y-503000D01*
X-1022033Y-502500D01*
X-1025183D01*
Y-512500D01*
X-1021333D01*
X-1020517Y-511833D01*
X-1020050Y-510833D01*
X-1019817Y-509667D01*
X-1020050Y-508500D01*
X-1020750Y-507500D01*
X-1021567Y-507167D01*
X-1025183D01*
G01X-1002567D02*
X-1002100Y-506667D01*
X-1001750Y-505834D01*
X-1001517Y-504667D01*
X-1001750Y-503667D01*
X-1002217Y-503000D01*
X-1003033Y-502500D01*
X-1006183D01*
Y-512500D01*
X-1002333D01*
X-1001517Y-511833D01*
X-1001050Y-510833D01*
X-1000817Y-509667D01*
X-1001050Y-508500D01*
X-1001750Y-507500D01*
X-1002567Y-507167D01*
X-1006183D01*
G01X-985083Y-515833D02*
X-986250Y-514167D01*
X-986833Y-512500D01*
Y-505834D01*
X-986250Y-504167D01*
X-985083Y-502500D01*
G01X-975000Y-512500D02*
X-975933Y-512333D01*
X-976750Y-511667D01*
X-977450Y-510667D01*
X-977917Y-509500D01*
X-978150Y-508167D01*
Y-506833D01*
X-977917Y-505500D01*
X-977450Y-504333D01*
X-976750Y-503333D01*
X-975933Y-502667D01*
X-975000Y-502500D01*
X-974067Y-502667D01*
X-973250Y-503333D01*
X-972550Y-504333D01*
X-972083Y-505500D01*
X-971850Y-506833D01*
Y-508167D01*
X-972083Y-509500D01*
X-972550Y-510667D01*
X-973250Y-511667D01*
X-974067Y-512333D01*
X-975000Y-512500D01*
G01X-967950Y-511167D02*
X-967017Y-512000D01*
X-965967Y-512500D01*
X-965033D01*
X-964100Y-512000D01*
X-963400Y-511167D01*
X-963050Y-510000D01*
X-963283Y-508834D01*
X-963867Y-507833D01*
X-964917Y-507167D01*
X-966317Y-506833D01*
X-967133Y-506167D01*
X-967483Y-505000D01*
X-967250Y-503833D01*
X-966667Y-503000D01*
X-965850Y-502500D01*
X-965033D01*
X-964217Y-502833D01*
X-963517Y-503667D01*
G01X-958333Y-512500D02*
Y-502500D01*
X-955533D01*
X-954600Y-503000D01*
X-953900Y-504167D01*
X-953667Y-505500D01*
X-953900Y-506833D01*
X-954483Y-507833D01*
X-955533Y-508334D01*
X-958333D01*
G01X-945917Y-515833D02*
X-944750Y-514167D01*
X-944167Y-512500D01*
Y-505834D01*
X-944750Y-504167D01*
X-945917Y-502500D01*
G01X-926995Y-153500D02*
X-922305Y-144000D01*
G01X-926995D02*
X-922305Y-153500D01*
G01X-915550D02*
X-914768Y-153342D01*
X-913875Y-152867D01*
X-913317Y-152075D01*
X-913093Y-150967D01*
X-913317Y-149859D01*
X-913987Y-148908D01*
X-914992Y-148433D01*
X-916108D01*
X-916778Y-148117D01*
X-917337Y-147325D01*
X-917560Y-146217D01*
X-917225Y-145108D01*
X-916443Y-144317D01*
X-915550Y-144000D01*
X-914657Y-144317D01*
X-913875Y-145108D01*
X-913540Y-146217D01*
X-913763Y-147325D01*
X-914322Y-148117D01*
X-914992Y-148433D01*
X-916108D01*
X-917113Y-148908D01*
X-917783Y-149859D01*
X-918007Y-150967D01*
X-917783Y-152075D01*
X-917225Y-152867D01*
X-916332Y-153342D01*
X-915550Y-153500D01*
G01X-906450D02*
X-905668Y-153342D01*
X-904775Y-152867D01*
X-904217Y-152075D01*
X-903993Y-150967D01*
X-904217Y-149859D01*
X-904887Y-148908D01*
X-905892Y-148433D01*
X-907008D01*
X-907678Y-148117D01*
X-908237Y-147325D01*
X-908460Y-146217D01*
X-908125Y-145108D01*
X-907343Y-144317D01*
X-906450Y-144000D01*
X-905557Y-144317D01*
X-904775Y-145108D01*
X-904440Y-146217D01*
X-904663Y-147325D01*
X-905222Y-148117D01*
X-905892Y-148433D01*
X-907008D01*
X-908013Y-148908D01*
X-908683Y-149859D01*
X-908907Y-150967D01*
X-908683Y-152075D01*
X-908125Y-152867D01*
X-907232Y-153342D01*
X-906450Y-153500D01*
G01X-897573D02*
X-897350Y-151442D01*
X-897015Y-149700D01*
X-896568Y-148117D01*
X-896010Y-146375D01*
X-895117Y-144000D01*
X-899583D01*
G01X-890707Y-152075D02*
X-890037Y-152867D01*
X-889255Y-153342D01*
X-888250Y-153500D01*
X-887245Y-153183D01*
X-886463Y-152550D01*
X-885905Y-151442D01*
X-885793Y-150175D01*
X-886017Y-148908D01*
X-886575Y-148117D01*
X-887357Y-147483D01*
X-888138Y-147325D01*
X-888920Y-147483D01*
X-889925Y-148117D01*
X-889590Y-144000D01*
X-886575D01*
G01X-879373Y-153500D02*
X-879150Y-151442D01*
X-878815Y-149700D01*
X-878368Y-148117D01*
X-877810Y-146375D01*
X-876917Y-144000D01*
X-881383D01*
G01X-870050Y-153500D02*
Y-144000D01*
X-871390Y-145900D01*
G01Y-153500D02*
X-868710D01*
G01X-862402Y-150333D02*
X-859498D01*
G01X-851850Y-144000D02*
X-852743Y-144317D01*
X-853413Y-145108D01*
X-853860Y-146058D01*
X-854195Y-147325D01*
X-854307Y-148750D01*
X-854195Y-150175D01*
X-853860Y-151442D01*
X-853413Y-152392D01*
X-852743Y-153183D01*
X-851850Y-153500D01*
X-850957Y-153183D01*
X-850287Y-152392D01*
X-849840Y-151442D01*
X-849505Y-150175D01*
X-849393Y-148750D01*
X-849505Y-147325D01*
X-849840Y-146058D01*
X-850287Y-145108D01*
X-850957Y-144317D01*
X-851850Y-144000D01*
G01X-842750D02*
X-843643Y-144317D01*
X-844313Y-145108D01*
X-844760Y-146058D01*
X-845095Y-147325D01*
X-845207Y-148750D01*
X-845095Y-150175D01*
X-844760Y-151442D01*
X-844313Y-152392D01*
X-843643Y-153183D01*
X-842750Y-153500D01*
X-841857Y-153183D01*
X-841187Y-152392D01*
X-840740Y-151442D01*
X-840405Y-150175D01*
X-840293Y-148750D01*
X-840405Y-147325D01*
X-840740Y-146058D01*
X-841187Y-145108D01*
X-841857Y-144317D01*
X-842750Y-144000D01*
G01X-836107Y-152075D02*
X-835437Y-152867D01*
X-834655Y-153342D01*
X-833650Y-153500D01*
X-832645Y-153183D01*
X-831863Y-152550D01*
X-831305Y-151442D01*
X-831193Y-150175D01*
X-831417Y-148908D01*
X-831975Y-148117D01*
X-832757Y-147483D01*
X-833538Y-147325D01*
X-834320Y-147483D01*
X-835325Y-148117D01*
X-834990Y-144000D01*
X-831975D01*
G01X-902000Y-470000D02*
Y-460000D01*
X-903400Y-462000D01*
G01Y-470000D02*
X-900600D01*
G01X-892500Y-470333D02*
X-892733Y-470167D01*
Y-469833D01*
X-892500Y-469667D01*
X-892267Y-469833D01*
Y-470167D01*
X-892500Y-470333D01*
G01Y-465834D02*
X-892733Y-465667D01*
Y-465333D01*
X-892500Y-465167D01*
X-892267Y-465333D01*
Y-465667D01*
X-892500Y-465834D01*
G01X-883000Y-470000D02*
Y-460000D01*
X-884400Y-462000D01*
G01Y-470000D02*
X-881600D01*
G01X-785060Y-472187D02*
X-784127Y-473020D01*
X-783077Y-473520D01*
X-782143D01*
X-781210Y-473020D01*
X-780510Y-472187D01*
X-780160Y-471020D01*
X-780393Y-469854D01*
X-780977Y-468853D01*
X-782027Y-468187D01*
X-783427Y-467853D01*
X-784243Y-467187D01*
X-784593Y-466020D01*
X-784360Y-464853D01*
X-783777Y-464020D01*
X-782960Y-463520D01*
X-782143D01*
X-781327Y-463853D01*
X-780627Y-464687D01*
G01X-775560Y-473520D02*
Y-463520D01*
G01X-770660D02*
Y-473520D01*
G01Y-468520D02*
X-775560D01*
G01X-766527Y-473520D02*
X-763610Y-463520D01*
X-760693Y-473520D01*
G01X-761743Y-470020D02*
X-765477D01*
G01X-757610Y-463520D02*
X-755977Y-473520D01*
X-754110Y-463520D01*
X-752243Y-473520D01*
X-750610Y-463520D01*
G01X-668067Y-470500D02*
X-667367Y-471667D01*
X-666433Y-472333D01*
X-665383Y-472500D01*
X-664450Y-472333D01*
X-663517Y-471500D01*
X-662933Y-470500D01*
X-662817Y-469500D01*
X-663050Y-468334D01*
X-663867Y-467500D01*
X-664683Y-467167D01*
X-665733D01*
G01X-664683D02*
X-663983Y-466667D01*
X-663400Y-465834D01*
X-663167Y-464833D01*
X-663400Y-463833D01*
X-663983Y-463000D01*
X-665033Y-462500D01*
X-666083Y-462667D01*
X-667133Y-463333D01*
G01X-656000Y-462500D02*
X-656933Y-462833D01*
X-657633Y-463667D01*
X-658100Y-464667D01*
X-658450Y-466000D01*
X-658567Y-467500D01*
X-658450Y-469000D01*
X-658100Y-470333D01*
X-657633Y-471334D01*
X-656933Y-472167D01*
X-656000Y-472500D01*
X-655067Y-472167D01*
X-654367Y-471334D01*
X-653900Y-470333D01*
X-653550Y-469000D01*
X-653433Y-467500D01*
X-653550Y-466000D01*
X-653900Y-464667D01*
X-654367Y-463667D01*
X-655067Y-462833D01*
X-656000Y-462500D01*
G01X-648017Y-469167D02*
X-644983D01*
G01X-639917Y-472500D02*
X-637000Y-462500D01*
X-634083Y-472500D01*
G01X-635133Y-469000D02*
X-638867D01*
G01X-629833Y-472500D02*
Y-462500D01*
X-627033D01*
X-626100Y-463000D01*
X-625400Y-464167D01*
X-625167Y-465500D01*
X-625400Y-466833D01*
X-625983Y-467833D01*
X-627033Y-468334D01*
X-629833D01*
G01X-620333Y-472500D02*
Y-462500D01*
X-617417D01*
X-616483Y-463000D01*
X-615900Y-463667D01*
X-615667Y-465000D01*
X-615900Y-466333D01*
X-616600Y-467167D01*
X-617417Y-467667D01*
X-620333D01*
G01X-617417D02*
X-615667Y-472500D01*
G01X-610017Y-469167D02*
X-606983D01*
G01X-599000Y-472500D02*
Y-462500D01*
X-600400Y-464500D01*
G01Y-472500D02*
X-597600D01*
G01X-588100D02*
Y-462500D01*
X-592417Y-469667D01*
X-586583D01*
G54D29*
X-1263189Y-172598D03*
X-1266339D03*
X-1269488D03*
X-1272638D03*
X-1274213Y-162756D03*
X-1271063D03*
X-1267913D03*
X-1264764D03*
X-1247441Y-172598D03*
X-1250591D03*
X-1253740D03*
X-1256890D03*
X-1260039D03*
X-1261614Y-162756D03*
X-1258465D03*
X-1255315D03*
X-1252165D03*
X-1249016D03*
X-1231693Y-172598D03*
X-1234843D03*
X-1237992D03*
X-1241142D03*
X-1244291D03*
X-1245866Y-162756D03*
X-1242717D03*
X-1239567D03*
X-1236417D03*
X-1233268D03*
X-1215945Y-172598D03*
X-1219094D03*
X-1222244D03*
X-1225394D03*
X-1228543D03*
X-1230118Y-162756D03*
X-1226968D03*
X-1223819D03*
X-1220669D03*
X-1217520D03*
X-396260Y-172598D03*
X-399409D03*
X-402559D03*
X-404134Y-162756D03*
X-400984D03*
X-397835D03*
X-380512Y-172598D03*
X-383661D03*
X-386811D03*
X-389961D03*
X-393110D03*
X-394685Y-162756D03*
X-391535D03*
X-388386D03*
X-385236D03*
X-382087D03*
X-364764Y-172598D03*
X-367913D03*
X-371063D03*
X-374213D03*
X-377362D03*
X-378937Y-162756D03*
X-375787D03*
X-372638D03*
X-369488D03*
X-366339D03*
X-349016Y-172598D03*
X-352165D03*
X-355315D03*
X-358465D03*
X-361614D03*
X-363189Y-162756D03*
X-360039D03*
X-356890D03*
X-353740D03*
X-350591D03*
X-345866Y-172598D03*
X-347441Y-162756D03*
G54D39*
G01X-1519000Y-125359D02*
X-1524359D01*
G01X-1494193Y-169390D02*
X-1497043D01*
G01X-1484193D02*
X-1486693Y-166890D01*
G01X-1484193Y-149390D02*
X-1486693Y-146890D01*
G01X-1494193Y-149390D02*
X-1497043D01*
G01X-1484193Y-164390D02*
X-1486693Y-161890D01*
G01X-1489193Y-159390D02*
X-1491693Y-156890D01*
G01X-1494193Y-164390D02*
X-1497043D01*
G01X-1489193Y-154390D02*
X-1491693Y-151890D01*
Y-151849D01*
X-1491652D01*
G01X-1489193Y-134390D02*
X-1491693Y-131890D01*
G01X-1494193Y-144390D02*
X-1497043D01*
G01X-1489193Y-139390D02*
X-1491693Y-136890D01*
G01X-1484193Y-144390D02*
X-1486693Y-141890D01*
G01X-1489193Y-119390D02*
X-1491693Y-116890D01*
G01X-1494193Y-124390D02*
X-1497043D01*
G01X-1494193Y-129390D02*
X-1497043D01*
G01X-1484193Y-124390D02*
X-1486693Y-121890D01*
G01X-1484193Y-129390D02*
X-1486693Y-126890D01*
G01X-1494193Y-104390D02*
X-1497043D01*
G01X-1484193D02*
X-1486693Y-101890D01*
G01X-1484193Y-109390D02*
X-1486693Y-106890D01*
G01X-1489193Y-114390D02*
X-1491693Y-111890D01*
G01X-1494193Y-109390D02*
X-1494264D01*
X-1494352Y-109478D01*
X-1496108D01*
X-1496197Y-109390D01*
X-1497043D01*
G01X-1494193Y-89390D02*
X-1497043D01*
G01X-1484193D02*
X-1486693Y-86890D01*
G01X-1489193Y-94390D02*
X-1491693Y-91890D01*
G01X-1489193Y-99390D02*
X-1491693Y-96890D01*
G01X-1489193Y-79390D02*
X-1491693Y-76890D01*
G01X-1484193Y-84390D02*
X-1486693Y-81890D01*
G01X-1484193Y-79390D02*
X-1486693Y-76890D01*
G01X-1494193Y-84390D02*
X-1494310D01*
X-1497000Y-81700D01*
G01X-1494193Y-79390D02*
X-1496693Y-76890D01*
G01X-1494193Y-74390D02*
X-1496693Y-71890D01*
G01X-1484193Y-74390D02*
X-1486693Y-71890D01*
G01X-1489193Y-74390D02*
X-1491693Y-71890D01*
G01X-1464193Y-169390D02*
X-1466693Y-166890D01*
G01X-1474193Y-169390D02*
X-1476693Y-166890D01*
G01X-1474193Y-149390D02*
X-1476693Y-146890D01*
G01X-1474193Y-164390D02*
X-1476693Y-161890D01*
G01X-1479193Y-159390D02*
X-1481693Y-156890D01*
G01X-1479193Y-154390D02*
X-1481693Y-151890D01*
G01X-1469193Y-154390D02*
X-1471693Y-151890D01*
G01X-1469193Y-159390D02*
X-1471693Y-156890D01*
G01X-1464193Y-164390D02*
X-1466693Y-161890D01*
G01X-1479193Y-134390D02*
X-1481693Y-131890D01*
G01X-1469193Y-134390D02*
X-1471693Y-131890D01*
G01X-1479193Y-139390D02*
X-1481693Y-136890D01*
G01X-1469193Y-139390D02*
X-1471693Y-136890D01*
G01X-1464193Y-144390D02*
X-1466693Y-141890D01*
G01X-1474193Y-144390D02*
X-1476693Y-141890D01*
G01X-1464193Y-149390D02*
X-1466693Y-146890D01*
G01X-1479193Y-119390D02*
X-1481693Y-116890D01*
G01X-1469193Y-119390D02*
X-1471693Y-116890D01*
G01X-1464193Y-124390D02*
X-1466693Y-121890D01*
G01X-1474193Y-124390D02*
X-1476693Y-121890D01*
G01X-1464193Y-129390D02*
X-1466693Y-126890D01*
G01X-1474193Y-129390D02*
X-1476693Y-126890D01*
G01X-1479193Y-114390D02*
X-1481693Y-111890D01*
G01X-1474193Y-104390D02*
X-1476693Y-101890D01*
G01X-1464193Y-109390D02*
X-1466693Y-106890D01*
G01X-1474193Y-109390D02*
X-1476693Y-106890D01*
G01X-1469193Y-114390D02*
X-1471693Y-111890D01*
G01X-1479193Y-94390D02*
X-1481693Y-91890D01*
G01X-1479193Y-99390D02*
X-1481693Y-96890D01*
G01X-1464193Y-89390D02*
X-1466693Y-86890D01*
G01X-1474193Y-89390D02*
X-1476693Y-86890D01*
G01X-1469193Y-94390D02*
X-1471693Y-91890D01*
G01X-1469193Y-99390D02*
X-1471693Y-96890D01*
G01X-1464193Y-104390D02*
X-1466693Y-101890D01*
G01X-1474193Y-84390D02*
X-1476693Y-81890D01*
G01X-1459193Y-154390D02*
X-1461693Y-151890D01*
G01X-1459193Y-159390D02*
X-1461693Y-156890D01*
G01X-1459193Y-134390D02*
X-1461693Y-131890D01*
G01X-1459193Y-139390D02*
X-1461693Y-136890D01*
G01X-1459193Y-119390D02*
X-1461693Y-116890D01*
G01X-1459193Y-114390D02*
X-1461693Y-111890D01*
G01X-1459193Y-94390D02*
X-1461693Y-91890D01*
G01X-1459193Y-99390D02*
X-1461693Y-96890D01*
G01X-1391300Y-133200D02*
X-1387300D01*
G01X-1396100Y-131550D02*
X-1400100D01*
G01X-1356500Y-21159D02*
Y-25400D01*
X-1356700Y-25600D01*
G01X-1356500Y-16041D02*
X-1341891D01*
X-1341850Y-16000D01*
G01X-1324840Y-82120D02*
X-1324770Y-82050D01*
X-1322228D01*
G01Y-85650D02*
Y-88400D01*
G01X-1316728Y-85900D02*
Y-89200D01*
G01Y-80800D02*
X-1313050D01*
X-1313040Y-80810D01*
G01X-1310600Y-46690D02*
X-1310590Y-46700D01*
X-1307559D01*
G01X-1324500Y-21959D02*
Y-26959D01*
G01Y-16841D02*
X-1311109D01*
X-1311050Y-16900D01*
G01X-1302441Y-30200D02*
X-1298800D01*
G01X-1272638Y-172598D02*
Y-177998D01*
G01X-1263189Y-172598D02*
Y-177998D01*
G01X-1264764Y-162756D02*
Y-157250D01*
X-1264764Y-157350D01*
G01X-1274213Y-162756D02*
Y-157250D01*
X-1274213Y-157350D01*
G01X-1253740Y-172598D02*
Y-177998D01*
G01X-1255315Y-157350D02*
X-1255315Y-157250D01*
Y-162756D01*
G01X-1234843Y-172598D02*
Y-177998D01*
G01X-1241142Y-172598D02*
Y-178998D01*
G01X-1244291Y-172598D02*
Y-177998D01*
G01X-1236417Y-162756D02*
Y-157250D01*
X-1236418Y-157350D01*
G01X-1225394Y-172598D02*
Y-177998D01*
G01X-1215945Y-172598D02*
Y-177998D01*
G01X-1217520Y-157350D02*
X-1217520Y-157250D01*
Y-162756D01*
G01X-1226968D02*
Y-157250D01*
X-1226969Y-157350D01*
G01X-1174900Y-473500D02*
X-1171300Y-466100D01*
X-1171800Y-465700D01*
X-1175900Y-473200D01*
X-1176200Y-471200D01*
X-1172500Y-465400D01*
X-1175700Y-471300D01*
X-1176500Y-469800D01*
X-1172900Y-464900D01*
X-1173600Y-451800D01*
X-1173700Y-449900D01*
X-1182100D01*
X-1187400Y-473000D01*
X-1182400D01*
X-1177800Y-456000D01*
X-1177000Y-455900D01*
X-1176100Y-468500D01*
X-1173700Y-464500D01*
X-1174600Y-450800D01*
X-1181500Y-450900D01*
X-1186400Y-472100D01*
X-1183100D01*
X-1178300Y-454800D01*
X-1176600Y-455000D01*
X-1175500Y-466300D01*
X-1174600Y-464300D01*
X-1175400Y-451700D01*
X-1181000Y-451800D01*
X-1185300Y-471300D01*
X-1183800Y-471400D01*
X-1179000Y-454300D01*
X-1176200D01*
X-1175200Y-462200D01*
X-1176200Y-452500D01*
X-1180500Y-452800D01*
X-1184300Y-470600D01*
X-1179700Y-453400D01*
X-1176800D01*
G01X-1182820Y-448900D02*
X-1188360Y-473900D01*
X-1181580D01*
X-1177300Y-456700D01*
X-1176920Y-473900D01*
X-1172260D01*
X-1163400Y-456920D01*
X-1167240Y-473900D01*
X-1160380D01*
X-1154840Y-448900D01*
X-1164540D01*
X-1172540Y-464820D01*
X-1172880Y-448900D01*
X-1182820D01*
G01X-1187359Y-34900D02*
X-1190600D01*
X-1191500Y-34000D01*
G01X-1187487Y-18250D02*
X-1191000D01*
G01X-1155800Y-449500D02*
X-1161100Y-472900D01*
X-1166100Y-473000D01*
X-1166000Y-471900D01*
X-1161800Y-472100D01*
X-1161300Y-471000D01*
X-1165900Y-471100D01*
X-1165700Y-470000D01*
X-1161300D01*
X-1160800Y-469200D01*
X-1165300Y-469100D01*
X-1165200Y-468100D01*
X-1160700D01*
X-1160400Y-467100D01*
X-1165100Y-467200D01*
X-1164900Y-466300D01*
X-1160300Y-466200D01*
X-1160000Y-465200D01*
X-1164700Y-465300D01*
X-1164400Y-464200D01*
X-1159700Y-464300D01*
X-1159300Y-463100D01*
X-1164700Y-463500D01*
X-1164000Y-462500D01*
X-1159500Y-462600D01*
X-1159000Y-461700D01*
X-1163900D01*
X-1163600Y-460600D01*
X-1159100Y-460800D01*
X-1158800Y-459900D01*
X-1163200D01*
X-1163100Y-459200D01*
X-1158800D01*
X-1158300Y-458500D01*
X-1163000Y-458400D01*
X-1162900Y-457800D01*
X-1158400Y-457900D01*
X-1158200Y-457200D01*
X-1162500Y-457000D01*
X-1163100Y-456500D01*
X-1157800D01*
X-1157500Y-455500D01*
X-1156600Y-449800D01*
X-1164000D01*
X-1164500Y-450700D01*
X-1157600D01*
X-1157800Y-451700D01*
X-1165000Y-451600D01*
X-1165400Y-452400D01*
X-1157900Y-452500D01*
X-1157800Y-453500D01*
X-1165900Y-453200D01*
X-1166200Y-453900D01*
X-1158000Y-454300D01*
X-1158300Y-455300D01*
X-1166600Y-454800D01*
X-1158900Y-455900D01*
X-1167000Y-455600D01*
X-1163500Y-456400D01*
X-1167300Y-456300D01*
X-1171700Y-465200D01*
X-1169200Y-466400D01*
X-1164500Y-457200D01*
X-1166900Y-457100D01*
X-1170600Y-465200D01*
X-1169500Y-465500D01*
X-1166000Y-457800D01*
G01X-1170300Y-466300D02*
X-1174000Y-473600D01*
G01X-1169500Y-466900D02*
X-1172800Y-473000D01*
G01X-1182441Y-40500D02*
X-1179000D01*
G01X-1168487Y-10750D02*
X-1172000D01*
G01X-1168487Y-21750D02*
X-1171500D01*
G01X-1152800Y-456400D02*
X-1156600Y-473100D01*
X-1152200Y-473000D01*
X-1148300Y-456600D01*
X-1149500D01*
X-1152900Y-472000D01*
X-1155600Y-472300D01*
X-1152100Y-456500D01*
X-1150400Y-456400D01*
X-1153600Y-471200D01*
X-1154500Y-471400D01*
X-1151400Y-457200D01*
G01X-1153420Y-455700D02*
X-1157540Y-473900D01*
X-1151380D01*
X-1147440Y-455700D01*
X-1153420D01*
G01X-1151600Y-450100D02*
X-1146700Y-450000D01*
X-1147000Y-451000D01*
X-1151700D01*
G01X-1152020Y-448900D02*
X-1152660Y-451900D01*
X-1146380D01*
X-1145740Y-448900D01*
X-1152020D01*
G01X-1163441Y-38500D02*
X-1160000D01*
G01X-1129400Y-468900D02*
X-1131800Y-471900D01*
X-1136500Y-473700D01*
X-1142100Y-473600D01*
X-1144600Y-472300D01*
X-1145800Y-471000D01*
X-1146400Y-469500D01*
X-1146700Y-467600D01*
X-1146500Y-464600D01*
X-1145400Y-461200D01*
X-1143500Y-459100D01*
X-1140200Y-456900D01*
X-1136100Y-456200D01*
X-1132300Y-456400D01*
X-1129400Y-457900D01*
X-1127500Y-460900D01*
X-1132500Y-461000D01*
X-1133400Y-459200D01*
X-1135100Y-458100D01*
X-1136800Y-458000D01*
X-1138600Y-458900D01*
X-1140300Y-460700D01*
X-1141800Y-463600D01*
X-1142400Y-466600D01*
X-1141500Y-470400D01*
X-1140200Y-471500D01*
X-1138300Y-471600D01*
X-1136300Y-471400D01*
X-1134500Y-469100D01*
X-1130300Y-469000D01*
X-1132500Y-471200D01*
X-1134900Y-472000D01*
X-1137200Y-472800D01*
X-1142300Y-472700D01*
X-1144900Y-470600D01*
X-1145800Y-467400D01*
X-1145500Y-465100D01*
X-1144700Y-462000D01*
X-1143300Y-460200D01*
X-1139800Y-457700D01*
X-1135400Y-457000D01*
X-1131300Y-457600D01*
X-1128800Y-460100D01*
X-1132100D01*
X-1134300Y-457900D01*
X-1130100Y-458800D01*
X-1129500Y-459400D01*
X-1132600Y-459000D01*
G01X-1133300Y-461900D02*
Y-461420D01*
X-1133640Y-460240D01*
X-1134300Y-459200D01*
X-1135200Y-458900D01*
X-1136580D01*
X-1138060Y-459820D01*
X-1139360Y-461000D01*
X-1140240Y-462220D01*
X-1140880Y-463920D01*
X-1141300Y-465380D01*
X-1141500Y-467060D01*
Y-468020D01*
X-1141020Y-469220D01*
X-1139780Y-470700D01*
X-1137160D01*
X-1135840Y-469500D01*
X-1134980Y-468200D01*
X-1134940Y-468100D01*
X-1128180D01*
X-1128240Y-468240D01*
X-1128840Y-469340D01*
X-1129020Y-469800D01*
X-1129740Y-470700D01*
X-1130500Y-471460D01*
X-1131660Y-472420D01*
X-1132820Y-473200D01*
X-1133740Y-473740D01*
X-1136380Y-474500D01*
X-1141640D01*
X-1142540Y-474320D01*
X-1144220Y-473760D01*
X-1144900Y-473240D01*
X-1146240Y-471900D01*
X-1146780Y-471180D01*
X-1146940Y-470880D01*
X-1147320Y-469660D01*
X-1147500Y-468640D01*
Y-464780D01*
X-1146940Y-462540D01*
X-1146380Y-461580D01*
X-1145980Y-460780D01*
X-1145420Y-459880D01*
X-1143700Y-458140D01*
X-1142740Y-457380D01*
X-1142000Y-456820D01*
X-1140240Y-456040D01*
X-1139500Y-455660D01*
X-1138800Y-455480D01*
X-1137260Y-455300D01*
X-1134320D01*
X-1132020Y-455500D01*
X-1130940Y-455860D01*
X-1130580Y-456020D01*
X-1129260Y-456780D01*
X-1128940Y-457100D01*
X-1127820Y-458420D01*
X-1127060Y-460300D01*
X-1126900Y-460800D01*
Y-461900D01*
X-1133300D01*
G01X-1137900Y-458000D02*
X-1140300Y-459100D01*
X-1142500Y-460900D01*
X-1143900Y-462600D01*
X-1144800Y-467600D01*
X-1144200Y-470000D01*
X-1141000Y-472300D01*
X-1136400Y-472200D01*
X-1131600Y-469600D01*
X-1135400Y-470400D01*
X-1141100Y-471400D01*
X-1142100Y-470700D01*
X-1142700Y-469000D01*
X-1143100Y-467100D01*
X-1142700Y-464100D01*
X-1140500Y-459900D01*
X-1143400Y-463700D01*
X-1143600Y-465700D01*
X-1143900Y-467700D01*
X-1143000Y-469900D01*
G01X-1113500Y-459200D02*
X-1123500Y-459300D01*
X-1123700Y-460100D01*
X-1114300Y-460000D01*
X-1116500Y-460800D01*
X-1124200Y-461000D01*
X-1124400Y-461900D01*
X-1117600Y-461800D01*
X-1118800Y-462800D01*
X-1124500Y-462700D01*
X-1124600Y-463600D01*
X-1119300Y-463700D01*
X-1120100Y-464800D01*
X-1125000Y-464600D01*
Y-465500D01*
X-1120600Y-465700D01*
X-1120800Y-466700D01*
X-1125300Y-466500D01*
X-1125500Y-467400D01*
X-1121000Y-467600D01*
X-1121200Y-468700D01*
X-1125600Y-468400D01*
X-1125900Y-469100D01*
X-1121500Y-469500D01*
X-1121700Y-470700D01*
X-1126100Y-470000D01*
X-1126200Y-470700D01*
X-1121900Y-471200D01*
X-1122100Y-472000D01*
X-1126300Y-471700D01*
X-1126700Y-472300D01*
X-1122100Y-472700D01*
X-1122200Y-473100D01*
X-1126800Y-473200D01*
G01X-1114060Y-460760D02*
X-1114840Y-460920D01*
X-1115740Y-461140D01*
X-1116880Y-461820D01*
X-1117700Y-462640D01*
X-1118620Y-463340D01*
X-1118840Y-464020D01*
X-1119440Y-464820D01*
X-1119660Y-465480D01*
X-1120060Y-466280D01*
X-1120280Y-466960D01*
X-1120480Y-468360D01*
X-1120680Y-468940D01*
X-1120880Y-469940D01*
X-1121080Y-470540D01*
X-1121700Y-472980D01*
X-1121820Y-473900D01*
X-1127640D01*
X-1126920Y-471060D01*
X-1126720Y-470440D01*
X-1126500Y-468800D01*
X-1126320Y-467860D01*
X-1126120Y-467260D01*
X-1125920Y-466260D01*
X-1125720Y-465660D01*
X-1125300Y-464000D01*
X-1125120Y-462220D01*
X-1124920Y-461660D01*
X-1124720Y-460660D01*
X-1124520Y-460060D01*
X-1123720Y-456800D01*
X-1123580Y-455700D01*
X-1117880D01*
X-1118100Y-456160D01*
Y-458740D01*
X-1116500Y-457160D01*
X-1115780Y-456620D01*
X-1114680Y-456060D01*
X-1113560Y-455680D01*
X-1112460Y-455500D01*
X-1111720D01*
X-1112460Y-458440D01*
X-1114060Y-460760D01*
G01X-1123100Y-456500D02*
X-1118900Y-456600D01*
X-1118800Y-457600D01*
X-1123100Y-457500D01*
X-1123300Y-458500D01*
X-1113100Y-458400D01*
X-1112600Y-456400D01*
X-1116100Y-457600D01*
X-1113500D01*
G01X-1122128Y-175150D02*
X-1124878D01*
G01X-1122128Y-170650D02*
X-1124900D01*
G01X-1131361Y-179850D02*
X-1134579D01*
G01X-1131361D02*
X-1131311Y-179900D01*
G01X-1124700Y-180000D02*
X-1124800Y-179900D01*
X-1127689D01*
G01X-1121800Y-180000D02*
X-1124700D01*
G01X-1126575Y-136730D02*
Y-142362D01*
G01D02*
Y-147990D01*
G01X-1128150Y-110079D02*
Y-104831D01*
X-1128810Y-104171D01*
G01X-1105100Y-471100D02*
X-1104060D01*
X-1103780Y-470820D01*
X-1103200Y-470640D01*
X-1102080Y-469740D01*
X-1100800Y-468240D01*
X-1100380Y-467400D01*
X-1100180Y-467100D01*
X-1099960Y-466660D01*
X-1099540Y-465720D01*
X-1099320Y-465060D01*
X-1099100Y-464180D01*
Y-461220D01*
X-1099360Y-460200D01*
X-1099660Y-459900D01*
X-1100700Y-458640D01*
X-1101220Y-458300D01*
X-1103340D01*
X-1103700Y-458640D01*
X-1105300Y-459840D01*
X-1105760Y-460320D01*
X-1106180Y-460940D01*
X-1107060Y-462020D01*
X-1107260Y-462880D01*
X-1107660Y-463660D01*
X-1108100Y-465000D01*
Y-468640D01*
X-1107620Y-469600D01*
X-1107140Y-470340D01*
X-1105980Y-471100D01*
X-1105100D01*
G01X-1112540Y-460460D02*
X-1110680Y-458140D01*
X-1109940Y-457580D01*
X-1109000Y-456840D01*
X-1108480Y-456660D01*
X-1107940Y-456400D01*
X-1107740Y-456200D01*
X-1107480Y-456060D01*
X-1106880Y-455860D01*
X-1106480Y-455660D01*
X-1105960Y-455480D01*
X-1104600Y-455300D01*
X-1103440Y-455100D01*
X-1100940D01*
X-1098240Y-455480D01*
X-1097720Y-455660D01*
X-1097020Y-456020D01*
X-1096180Y-456640D01*
X-1095620Y-456820D01*
X-1095540Y-456900D01*
X-1094200Y-458440D01*
X-1093660Y-459520D01*
X-1093460Y-460100D01*
X-1093100Y-461020D01*
Y-464400D01*
X-1093420Y-465360D01*
X-1094300Y-465520D01*
X-1094720Y-465740D01*
X-1095320Y-465940D01*
X-1096120Y-466340D01*
X-1096720Y-466540D01*
X-1097100Y-466720D01*
X-1098100Y-466920D01*
X-1098520Y-467140D01*
X-1099160Y-467360D01*
X-1101180Y-468700D01*
X-1094660D01*
X-1095220Y-469800D01*
X-1095560Y-470320D01*
X-1097480Y-472220D01*
X-1099940Y-473740D01*
X-1102580Y-474500D01*
X-1108800D01*
X-1109300Y-474340D01*
X-1111220Y-473560D01*
X-1111720Y-473240D01*
X-1113240Y-471720D01*
X-1113560Y-471240D01*
X-1113760Y-470660D01*
X-1114140Y-469980D01*
X-1114320Y-469120D01*
X-1114500Y-468680D01*
Y-464980D01*
X-1114320Y-464260D01*
X-1114140Y-463720D01*
X-1113940Y-463320D01*
X-1113720Y-462660D01*
X-1113560Y-462000D01*
X-1111880Y-460320D01*
X-1112540Y-460460D01*
G01X-1099300Y-466400D02*
X-1093800Y-464400D01*
X-1093900Y-461100D01*
X-1094800Y-459000D01*
X-1096800Y-457300D01*
X-1100000Y-456100D01*
X-1102800Y-455900D01*
X-1106300Y-456300D01*
X-1109600Y-458100D01*
X-1111400Y-460500D01*
X-1112900Y-462600D01*
X-1113600Y-465600D01*
X-1113500Y-469100D01*
X-1112100Y-471900D01*
X-1109600Y-473300D01*
X-1105700Y-473800D01*
X-1101000Y-473400D01*
X-1098200Y-471800D01*
X-1096600Y-470100D01*
X-1096000Y-469500D01*
X-1100800Y-469700D01*
X-1102300Y-471100D01*
X-1097900Y-470400D01*
X-1100300Y-471800D01*
X-1103200Y-471400D01*
X-1100600Y-472600D01*
X-1103000D01*
X-1103700Y-471900D01*
X-1103400Y-473000D01*
X-1104600Y-471900D01*
X-1106200D01*
X-1104100Y-473100D01*
X-1107200Y-472700D01*
X-1110100Y-472100D01*
X-1111500Y-470900D01*
X-1112600Y-468600D01*
X-1112700Y-466000D01*
X-1112400Y-463700D01*
X-1111400Y-461600D01*
X-1109600Y-459500D01*
X-1108100Y-458200D01*
X-1105900Y-457200D01*
X-1102200Y-456700D01*
X-1099600Y-457300D01*
X-1097000Y-458400D01*
X-1095500Y-459500D01*
X-1094600Y-461900D01*
X-1094500Y-463900D01*
X-1098800Y-465200D01*
X-1098600Y-464000D01*
X-1095100Y-463100D01*
X-1095300Y-462000D01*
X-1098500Y-463000D01*
X-1098600Y-461700D01*
X-1095600Y-461300D01*
X-1095900Y-460200D01*
X-1098400Y-460700D01*
X-1098900Y-459900D01*
X-1096600Y-459400D01*
X-1097100Y-458900D01*
X-1099400Y-459000D01*
X-1098800Y-458500D01*
X-1100600Y-458000D01*
X-1102400Y-457400D01*
X-1104200Y-457500D01*
X-1106200Y-458100D01*
X-1107900Y-459000D01*
X-1110500Y-462200D01*
X-1111800Y-464800D01*
Y-467700D01*
X-1110700Y-470300D01*
X-1108700Y-472000D01*
X-1106600Y-471900D01*
X-1107900Y-470300D01*
X-1108900Y-468700D01*
Y-465500D01*
X-1107900Y-462300D01*
X-1106500Y-459900D01*
X-1104100Y-458200D01*
X-1108000Y-460000D01*
X-1108100Y-461500D01*
X-1108700Y-461200D01*
X-1110300Y-463600D01*
X-1111000Y-466000D01*
X-1110700Y-468100D01*
X-1109500Y-470600D01*
X-1107700Y-471400D01*
X-1109300Y-469100D01*
X-1109800Y-467600D01*
X-1108600Y-462200D01*
X-1110400Y-466800D01*
G01X-1113600Y-460900D02*
X-1112100Y-459000D01*
G01X-1117126Y-148090D02*
Y-142362D01*
G01X-1107677Y-136730D02*
Y-142362D01*
G01D02*
Y-148090D01*
G01X-1117126Y-142362D02*
Y-136730D01*
G01X-1093100Y-469400D02*
X-1087900Y-469700D01*
X-1086500Y-471400D01*
X-1083400Y-472300D01*
X-1081000Y-472000D01*
X-1079300Y-470600D01*
X-1079000Y-468900D01*
X-1079500Y-467700D01*
X-1080300Y-466600D01*
X-1081800Y-466000D01*
X-1083300Y-465500D01*
X-1085300Y-465000D01*
X-1087900Y-464000D01*
X-1089100Y-463200D01*
X-1089800Y-461000D01*
X-1089500Y-459000D01*
X-1088600Y-457700D01*
X-1086500Y-456700D01*
X-1084600Y-456100D01*
X-1081900Y-455900D01*
X-1079900Y-455800D01*
X-1076900Y-456300D01*
X-1075000Y-457000D01*
X-1073700Y-458000D01*
X-1073300Y-459400D01*
X-1077600Y-459500D01*
X-1078100Y-458800D01*
X-1074300Y-458500D01*
X-1074600Y-457800D01*
X-1078200Y-458200D01*
X-1076000Y-457400D01*
X-1079100Y-457700D01*
X-1077100Y-456900D01*
X-1080100Y-457300D01*
X-1079200Y-456600D01*
X-1083100Y-456800D01*
X-1080600Y-457300D01*
X-1083400Y-457700D01*
X-1083600Y-457000D01*
X-1087900Y-458400D01*
X-1084000Y-458100D01*
X-1088600Y-459100D01*
X-1088800Y-461500D01*
X-1087700Y-463600D01*
X-1084400Y-464300D01*
X-1081200Y-465400D01*
X-1078800Y-467300D01*
X-1078300Y-470500D01*
X-1079900Y-472600D01*
X-1083500Y-473300D01*
X-1085600Y-472600D01*
X-1088800Y-470500D01*
X-1092600Y-470200D01*
X-1092100Y-471800D01*
X-1091700Y-471300D01*
X-1089300Y-471500D01*
X-1091300Y-472300D01*
X-1088700Y-471600D01*
X-1084000Y-473500D01*
X-1089100D01*
X-1091000Y-472900D01*
X-1087200Y-472800D01*
X-1082700Y-473700D01*
X-1079000Y-473600D01*
X-1076500Y-472300D01*
X-1074700Y-470600D01*
X-1074300Y-467300D01*
X-1074800Y-465300D01*
X-1078800Y-463600D01*
X-1081600Y-462900D01*
X-1083400Y-462500D01*
X-1084800Y-461500D01*
X-1085000Y-458900D01*
X-1088100Y-459800D01*
X-1087200Y-462700D01*
X-1085000Y-463400D01*
X-1082000Y-464100D01*
X-1079600Y-465100D01*
X-1078200Y-466500D01*
X-1077700Y-468500D01*
X-1077500Y-470100D01*
X-1079200Y-472800D01*
X-1076800Y-471400D01*
X-1075300Y-470000D01*
X-1077300Y-470900D01*
X-1075000Y-468800D01*
X-1075200Y-466100D01*
X-1082700Y-462700D01*
X-1084200Y-462900D01*
X-1086600Y-461800D01*
X-1087200Y-460300D01*
X-1085800Y-459800D01*
X-1086600Y-461000D01*
X-1085300Y-460400D01*
X-1085600Y-461400D01*
X-1076700Y-466500D01*
X-1075900Y-467100D01*
X-1075700Y-468400D01*
X-1076800Y-469500D01*
X-1077800Y-466200D01*
X-1075900Y-468800D01*
G01X-1093780Y-468700D02*
X-1087100D01*
Y-469740D01*
X-1086800Y-470060D01*
X-1086520Y-470600D01*
X-1085820Y-470820D01*
X-1085660Y-471000D01*
X-1085120Y-471260D01*
X-1084400Y-471500D01*
X-1082360D01*
X-1080540Y-470600D01*
X-1080100Y-470140D01*
Y-469780D01*
X-1079840Y-469380D01*
X-1080380Y-467740D01*
X-1081440Y-466940D01*
X-1082560Y-466720D01*
X-1085740Y-465920D01*
X-1086940Y-465520D01*
X-1087600Y-465360D01*
X-1087740Y-465200D01*
X-1088540Y-464800D01*
X-1089140Y-464200D01*
X-1089540Y-464000D01*
X-1089800Y-463740D01*
X-1090000Y-463340D01*
X-1090180Y-463180D01*
X-1090500Y-462200D01*
Y-459800D01*
X-1090320Y-459260D01*
X-1090140Y-458500D01*
X-1090000Y-458260D01*
X-1089000Y-457260D01*
X-1088860Y-456940D01*
X-1085920Y-455480D01*
X-1083620Y-455100D01*
X-1082060Y-454900D01*
X-1080520D01*
X-1078580Y-455100D01*
X-1076240Y-455480D01*
X-1075120Y-455860D01*
X-1074800Y-456020D01*
X-1073680Y-456760D01*
X-1073160Y-457300D01*
X-1072620Y-458020D01*
X-1072500Y-458240D01*
Y-460300D01*
X-1078500D01*
Y-459200D01*
X-1079580Y-458380D01*
X-1080160Y-458100D01*
X-1082380D01*
X-1083280Y-458360D01*
X-1084020Y-458940D01*
X-1084340Y-459900D01*
X-1084060Y-460720D01*
X-1083740Y-461340D01*
X-1081860Y-462280D01*
X-1079400Y-462500D01*
X-1078660Y-462680D01*
X-1078100Y-462860D01*
X-1076500Y-463460D01*
X-1075320Y-463860D01*
X-1075060Y-464000D01*
X-1073820Y-465220D01*
X-1073480Y-466260D01*
X-1073300Y-467160D01*
Y-468420D01*
X-1073860Y-470700D01*
X-1074000Y-470960D01*
X-1075140Y-472300D01*
X-1075280Y-472440D01*
X-1076600Y-473380D01*
X-1077320Y-473740D01*
X-1079600Y-474500D01*
X-1088240D01*
X-1089160Y-474320D01*
X-1089920Y-474120D01*
X-1090860Y-473760D01*
X-1091560Y-473400D01*
X-1092700Y-472460D01*
X-1093180Y-471980D01*
X-1093340Y-471480D01*
X-1093520Y-471100D01*
X-1093700Y-470320D01*
X-1093780Y-468700D01*
G01X-1095100D02*
X-1092800D01*
G01X-1099028Y-170650D02*
X-1096278D01*
G01X-1096200Y-175150D02*
X-1099028D01*
G01X-1092111Y-179700D02*
X-1095500D01*
X-1095600Y-179600D01*
G01D02*
X-1095650Y-179650D01*
X-1099028D01*
G01X-1098228Y-136730D02*
Y-142362D01*
G01D02*
Y-148090D01*
G01X-1099803Y-110079D02*
Y-104976D01*
X-1099010Y-104183D01*
G01X-1058300Y-469400D02*
X-1055400Y-467100D01*
X-1053900Y-463700D01*
X-1054400Y-461200D01*
X-1055900Y-459900D01*
X-1054800Y-463500D01*
X-1055400Y-463600D01*
X-1054600Y-464500D01*
X-1055700D01*
X-1055400Y-465300D01*
X-1056200Y-466800D01*
G01X-1059300Y-457700D02*
X-1059100Y-455600D01*
X-1055200Y-456300D01*
X-1052700Y-457900D01*
X-1051100Y-460800D01*
X-1050900Y-465200D01*
X-1052900Y-469400D01*
X-1055300Y-471900D01*
X-1059000Y-473500D01*
X-1066000D01*
X-1068000Y-471900D01*
X-1070200Y-468700D01*
X-1070600Y-464500D01*
X-1069000Y-460500D01*
X-1066000Y-457500D01*
X-1063000Y-456500D01*
X-1059200Y-456000D01*
X-1053000Y-458500D01*
X-1052000Y-461500D01*
Y-465700D01*
X-1053400Y-468600D01*
X-1055700Y-471000D01*
X-1058900Y-472600D01*
X-1063700Y-473000D01*
X-1065900Y-473600D01*
X-1068300Y-472900D01*
X-1070600Y-469300D01*
X-1065100Y-472600D01*
X-1060800Y-472200D01*
X-1057200Y-470700D01*
X-1055200Y-469100D01*
X-1053300Y-466500D01*
X-1052500Y-463400D01*
X-1052900Y-460100D01*
X-1057000Y-457400D01*
X-1058700Y-457200D01*
X-1057000Y-458500D01*
X-1055100Y-459800D01*
X-1053800Y-460900D01*
X-1053400Y-463100D01*
X-1053600Y-465600D01*
X-1054800Y-467500D01*
X-1056400Y-469200D01*
X-1058500Y-470200D01*
X-1060200Y-470700D01*
X-1061500Y-471400D01*
X-1063300Y-471600D01*
X-1065400Y-471500D01*
X-1069000Y-469300D01*
X-1069600Y-466400D01*
X-1069700Y-463700D01*
X-1068600Y-461200D01*
X-1066700Y-459200D01*
X-1063900Y-457600D01*
X-1061100Y-457000D01*
X-1059600D01*
X-1060200Y-457500D01*
X-1063300Y-458000D01*
X-1065300Y-459500D01*
X-1066900Y-460600D01*
X-1067900Y-462100D01*
X-1068800Y-464300D01*
X-1068700Y-466900D01*
X-1068200Y-469100D01*
X-1066900Y-470200D01*
X-1064300Y-470900D01*
X-1065700Y-469300D01*
X-1065800Y-465900D01*
X-1065300Y-462900D01*
X-1061200Y-458200D01*
X-1063600Y-458900D01*
X-1066400Y-461300D01*
X-1067800Y-464200D01*
Y-467200D01*
X-1067400Y-469300D01*
X-1066300Y-469700D01*
X-1067100Y-466400D01*
X-1066600Y-463400D01*
X-1064700Y-460000D01*
X-1062600Y-458800D01*
X-1065300Y-461700D01*
X-1066700Y-467400D01*
G01X-1060840Y-455100D02*
X-1057160D01*
X-1055260Y-455480D01*
X-1054740Y-455640D01*
X-1053380Y-456420D01*
X-1052660Y-456800D01*
X-1052020Y-457420D01*
X-1051820Y-458020D01*
X-1051200Y-458660D01*
X-1051000Y-459060D01*
X-1050840Y-459200D01*
X-1050700Y-459780D01*
Y-460140D01*
X-1050400Y-460460D01*
X-1050280Y-460680D01*
X-1050100Y-461740D01*
Y-464240D01*
X-1050280Y-465160D01*
X-1050480Y-465980D01*
X-1050680Y-467120D01*
X-1051220Y-468180D01*
X-1051840Y-469020D01*
X-1052040Y-469600D01*
X-1052740Y-470500D01*
X-1054480Y-472240D01*
X-1055000Y-472580D01*
X-1055420Y-472780D01*
X-1056220Y-473380D01*
X-1056920Y-473740D01*
X-1059380Y-474500D01*
X-1065600D01*
X-1067860Y-473740D01*
X-1068160Y-473600D01*
X-1069500Y-472460D01*
X-1069820Y-472120D01*
X-1070380Y-471200D01*
X-1071140Y-469860D01*
X-1071300Y-469400D01*
Y-464580D01*
X-1071120Y-463880D01*
X-1070740Y-462900D01*
X-1070540Y-462320D01*
X-1069980Y-461000D01*
X-1068840Y-459500D01*
X-1066900Y-457560D01*
X-1066180Y-457020D01*
X-1065400Y-456620D01*
X-1064440Y-456040D01*
X-1063500Y-455660D01*
X-1062940Y-455480D01*
X-1060840Y-455100D01*
G01X-1057800Y-458580D02*
X-1057000Y-459120D01*
X-1056760Y-459840D01*
X-1056340Y-460460D01*
X-1056100Y-461640D01*
Y-463760D01*
X-1056320Y-464860D01*
X-1056720Y-466060D01*
X-1056940Y-466920D01*
X-1057200Y-467460D01*
X-1057640Y-467880D01*
X-1058040Y-468480D01*
X-1059960Y-470420D01*
X-1061020Y-470840D01*
X-1061420Y-471100D01*
X-1062720D01*
X-1063340Y-470840D01*
X-1063860Y-470600D01*
X-1064360Y-470080D01*
X-1064820Y-469400D01*
X-1065100Y-468840D01*
Y-464920D01*
X-1064880Y-464120D01*
X-1064420Y-462780D01*
X-1064160Y-462520D01*
X-1063620Y-461700D01*
X-1063200Y-460840D01*
X-1062500Y-460140D01*
X-1062120Y-459860D01*
X-1061720Y-459360D01*
X-1060600Y-458580D01*
X-1060040Y-458300D01*
X-1058360D01*
X-1057800Y-458580D01*
G01X-1040300Y-459100D02*
X-1041400Y-464800D01*
G01X-1044800Y-458200D02*
X-1041400D01*
X-1044300Y-472700D01*
X-1047400Y-472300D01*
X-1044100Y-458800D01*
X-1042400Y-459100D01*
X-1045100Y-471900D01*
X-1046500D01*
X-1043400Y-459700D01*
X-1045600Y-471500D01*
G01X-1036600Y-449900D02*
X-1036800Y-451300D01*
X-1038600Y-452400D01*
X-1039800Y-456100D01*
X-1033700Y-456500D01*
X-1032300Y-452100D01*
X-1028400Y-452000D01*
X-1028900Y-455400D01*
X-1027200Y-456600D01*
X-1025900Y-456800D01*
X-1026200Y-458200D01*
X-1030000Y-458400D01*
X-1031800Y-468900D01*
X-1030400Y-471700D01*
X-1029400D01*
X-1029600Y-473300D01*
X-1033100Y-473400D01*
X-1036100Y-472800D01*
X-1036200Y-470500D01*
X-1035900Y-467100D01*
X-1034400Y-461400D01*
X-1033800Y-458800D01*
X-1033500Y-458400D01*
X-1035000Y-458200D01*
X-1039600D01*
X-1040800Y-458300D01*
X-1043600Y-473200D01*
X-1048000Y-473000D01*
X-1045100Y-459400D01*
X-1044900Y-458400D01*
X-1048700D01*
X-1048100Y-456600D01*
X-1044900Y-456400D01*
X-1045200Y-457700D01*
X-1047600Y-457500D01*
X-1026500D01*
G01X-1049580Y-459100D02*
X-1048740Y-455700D01*
X-1044900D01*
Y-454780D01*
X-1044720Y-454060D01*
X-1044340Y-452920D01*
X-1043940Y-452120D01*
X-1043740Y-451520D01*
X-1043600Y-451260D01*
X-1042340Y-450000D01*
X-1042080Y-449860D01*
X-1040580Y-449480D01*
X-1039440Y-449300D01*
X-1036140D01*
X-1035440Y-449400D01*
X-1035480Y-449540D01*
X-1035680Y-450360D01*
X-1035880Y-451280D01*
X-1036000Y-451900D01*
X-1036740D01*
X-1037060Y-452200D01*
X-1037860Y-452600D01*
X-1038220Y-452980D01*
X-1038480Y-453740D01*
X-1038960Y-455700D01*
X-1034020D01*
X-1033720Y-455080D01*
X-1033500Y-453400D01*
X-1032940Y-451100D01*
X-1027260D01*
X-1027280Y-451180D01*
X-1027480Y-452780D01*
X-1027860Y-454280D01*
X-1028100Y-454760D01*
Y-455700D01*
X-1024800D01*
X-1024880Y-455940D01*
X-1025080Y-456940D01*
X-1025280Y-457540D01*
X-1025480Y-458560D01*
X-1025620Y-459100D01*
X-1029100D01*
Y-460000D01*
X-1029280Y-460540D01*
X-1029480Y-461540D01*
X-1029680Y-462140D01*
X-1029880Y-462960D01*
X-1030100Y-464000D01*
X-1030280Y-465560D01*
X-1030480Y-466140D01*
X-1030680Y-467140D01*
X-1030880Y-467740D01*
X-1031040Y-468400D01*
X-1031300Y-468660D01*
Y-469800D01*
X-1030300Y-470560D01*
X-1029940Y-470900D01*
X-1028220D01*
X-1028680Y-472780D01*
X-1028880Y-474120D01*
Y-474140D01*
X-1030720Y-474300D01*
X-1032860D01*
X-1034380Y-474120D01*
X-1035860Y-473740D01*
X-1036640Y-473280D01*
X-1036960Y-472660D01*
X-1037100Y-472280D01*
Y-470160D01*
X-1036920Y-469260D01*
X-1036700Y-468640D01*
X-1036500Y-466840D01*
X-1036320Y-466260D01*
X-1036120Y-465260D01*
X-1035920Y-464660D01*
X-1035720Y-463660D01*
X-1035520Y-463060D01*
X-1035320Y-462060D01*
X-1035120Y-461440D01*
X-1034820Y-459100D01*
X-1039900D01*
Y-460220D01*
X-1040280Y-461780D01*
X-1040480Y-463380D01*
X-1041280Y-466540D01*
X-1041480Y-467140D01*
X-1041700Y-468200D01*
X-1041880Y-469760D01*
X-1042080Y-470340D01*
X-1042280Y-471360D01*
X-1042480Y-472140D01*
X-1042680Y-472740D01*
X-1042880Y-473740D01*
X-1042940Y-473900D01*
X-1049140D01*
X-1048300Y-470620D01*
X-1048100Y-469020D01*
X-1047920Y-468260D01*
X-1047720Y-467660D01*
X-1047520Y-466660D01*
X-1047320Y-466060D01*
X-1047120Y-465060D01*
X-1046920Y-464460D01*
X-1046700Y-463400D01*
X-1046500Y-462020D01*
X-1046140Y-460500D01*
X-1045900Y-460040D01*
Y-459100D01*
X-1049580D01*
G01X-1038400Y-451100D02*
X-1040600Y-455800D01*
X-1043300D01*
X-1041400Y-451300D01*
X-1038900Y-451000D01*
X-1041200Y-455000D01*
X-1042000Y-455100D01*
X-1040500Y-452000D01*
G01X-1037500Y-449800D02*
X-1037800Y-451000D01*
X-1038500Y-450100D01*
X-1042000Y-450700D01*
X-1043100Y-452300D01*
X-1044100Y-455100D01*
X-1044200Y-456600D01*
X-1036600Y-456800D01*
G01X-1048000Y-43989D02*
X-1051089D01*
X-1051200Y-44100D01*
G01D02*
X-1051250Y-44050D01*
X-1054228D01*
G01X-1047289Y-23000D02*
Y-26300D01*
G01D02*
X-1047200Y-26389D01*
Y-29400D01*
G01X-1031100Y-472500D02*
X-1031400Y-470900D01*
X-1031900Y-472200D01*
X-1035200D01*
Y-467600D01*
X-1032000Y-453700D01*
X-1030500Y-453800D01*
X-1030000Y-456700D01*
X-1033400Y-471900D01*
X-1034300Y-471600D01*
X-1034200Y-467100D01*
X-1031400Y-454500D01*
X-1030700Y-456500D01*
X-1033700Y-470600D01*
X-1032700Y-461100D01*
G01X-1032000Y-452900D02*
X-1029300D01*
X-1028000Y-457000D01*
X-1029500Y-453600D01*
X-1029100Y-457300D01*
X-1032800Y-472800D01*
X-1030200Y-472600D01*
G01X-649700Y-125359D02*
X-643741D01*
X-643700Y-125400D01*
G01X-614114Y-169390D02*
X-616614Y-166890D01*
G01X-624114Y-169390D02*
X-626964D01*
G01X-614114Y-164390D02*
X-616614Y-161890D01*
G01X-619114Y-154390D02*
X-621614Y-151890D01*
Y-151849D01*
X-621573D01*
G01X-619114Y-159390D02*
X-621614Y-156890D01*
G01X-624114Y-164390D02*
X-626964D01*
G01X-624114Y-149390D02*
X-625290D01*
X-627200Y-151300D01*
G01X-614114Y-149390D02*
X-616614Y-146890D01*
G01X-614114Y-144390D02*
X-616614Y-141890D01*
G01X-619114Y-134390D02*
X-621614Y-131890D01*
G01X-619114Y-139390D02*
X-621614Y-136890D01*
G01X-624114Y-144390D02*
Y-144086D01*
X-626900Y-141300D01*
G01X-628700Y-130100D02*
X-627990Y-129390D01*
X-624114D01*
G01X-614114Y-124390D02*
X-616614Y-121890D01*
G01X-614114Y-129390D02*
X-616614Y-126890D01*
G01X-619114Y-119390D02*
X-621614Y-116890D01*
G01X-624114Y-124390D02*
X-621614Y-121890D01*
G01X-614114Y-104390D02*
X-616614Y-101890D01*
G01X-614114Y-109390D02*
X-616614Y-106890D01*
G01X-624114Y-109390D02*
X-624185D01*
X-624273Y-109478D01*
X-626030D01*
X-626118Y-109390D01*
X-626964D01*
G01X-624114Y-104390D02*
X-626964D01*
G01X-619114Y-114390D02*
X-621614Y-111890D01*
G01X-614114Y-89390D02*
X-616614Y-86890D01*
G01X-624114Y-89390D02*
X-626964D01*
G01X-619114Y-94390D02*
X-621614Y-91890D01*
G01X-619114Y-99390D02*
X-621614Y-96890D01*
G01X-614114Y-84390D02*
X-616614Y-81890D01*
G01X-619114Y-79390D02*
X-621614Y-76890D01*
G01X-614114Y-79390D02*
X-616614Y-76890D01*
G01X-626625Y-81614D02*
X-626359D01*
Y-82145D01*
X-624114Y-84390D01*
G01X-614114Y-74390D02*
X-616614Y-71890D01*
G01X-619114Y-74390D02*
X-621614Y-71890D01*
G01X-624114Y-74390D02*
X-626614Y-71890D01*
G01X-624114Y-79390D02*
X-626614Y-76890D01*
G01X-604114Y-169390D02*
X-606614Y-166890D01*
G01X-604114Y-149390D02*
X-606614Y-146890D01*
G01X-604114Y-164390D02*
X-606614Y-161890D01*
G01X-609114Y-159390D02*
X-611614Y-156890D01*
G01X-609114Y-154390D02*
X-611614Y-151890D01*
G01X-599114Y-154390D02*
X-601614Y-151890D01*
G01X-599114Y-159390D02*
X-601614Y-156890D01*
G01X-609114Y-134390D02*
X-611614Y-131890D01*
G01X-609114Y-139390D02*
X-611614Y-136890D01*
G01X-599114Y-139390D02*
X-601614Y-136890D01*
G01X-604114Y-144390D02*
X-606614Y-141890D01*
G01X-599114Y-134390D02*
X-601614Y-131890D01*
G01X-609114Y-119390D02*
X-611614Y-116890D01*
G01X-599114Y-119390D02*
X-601614Y-116890D01*
G01X-604114Y-124390D02*
X-606614Y-121890D01*
G01X-604114Y-129390D02*
X-606614Y-126890D01*
G01X-609114Y-114390D02*
X-611614Y-111890D01*
G01X-604114Y-104390D02*
X-606614Y-101890D01*
G01X-604114Y-109390D02*
X-606614Y-106890D01*
G01X-599114Y-114390D02*
X-601614Y-111890D01*
G01X-609114Y-94390D02*
X-611614Y-91890D01*
G01X-609114Y-99390D02*
X-611614Y-96890D01*
G01X-604114Y-89390D02*
X-606614Y-86890D01*
G01X-599114Y-94390D02*
X-601614Y-91890D01*
G01X-599114Y-99390D02*
X-601614Y-96890D01*
G01X-604114Y-84390D02*
X-606614Y-81890D01*
G01X-594114Y-169390D02*
X-596614Y-166890D01*
G01X-594114Y-164390D02*
X-596614Y-161890D01*
G01X-594114Y-149390D02*
X-596614Y-146890D01*
G01X-589114Y-154390D02*
X-591614Y-151890D01*
G01X-589114Y-159390D02*
X-591614Y-156890D01*
G01X-594114Y-144390D02*
X-596614Y-141890D01*
G01X-589114Y-134390D02*
X-591614Y-131890D01*
G01X-589114Y-139390D02*
X-591614Y-136890D01*
G01X-594114Y-124390D02*
X-596614Y-121890D01*
G01X-594114Y-129390D02*
X-596614Y-126890D01*
G01X-589114Y-119390D02*
X-591614Y-116890D01*
G01X-594114Y-109390D02*
X-596614Y-106890D01*
G01X-594114Y-104390D02*
X-596614Y-101890D01*
G01X-589114Y-114390D02*
X-591614Y-111890D01*
G01X-594114Y-89390D02*
X-596614Y-86890D01*
G01X-589114Y-94390D02*
X-591614Y-91890D01*
G01X-589114Y-99390D02*
X-591614Y-96890D01*
G01X-486421Y-21159D02*
Y-26159D01*
G01Y-16041D02*
X-486380Y-16000D01*
X-471771D01*
G01X-453628Y-85550D02*
Y-88300D01*
G01X-448128Y-85800D02*
Y-88800D01*
G01X-453628Y-81950D02*
X-456170D01*
X-456240Y-82020D01*
G01X-444440Y-80710D02*
X-444450Y-80700D01*
X-448128D01*
G01X-454421Y-21959D02*
Y-26959D01*
G01Y-16841D02*
X-441030D01*
X-440971Y-16900D01*
G01X-442000Y-29480D02*
X-441980Y-29500D01*
X-438959D01*
G01X-402559Y-172598D02*
Y-177998D01*
G01X-404134Y-162756D02*
Y-157250D01*
X-404134Y-157350D01*
G01X-383661Y-172598D02*
Y-177998D01*
G01X-393110Y-172598D02*
Y-177998D01*
G01X-385237Y-157350D02*
X-385236Y-157250D01*
Y-162756D01*
G01X-394685D02*
Y-157250D01*
X-394685Y-157350D01*
G01X-364764Y-172598D02*
Y-177998D01*
G01X-371063Y-172598D02*
Y-178998D01*
G01X-374213Y-172598D02*
Y-177998D01*
G01X-366339Y-162756D02*
Y-157250D01*
X-366339Y-157350D01*
G01X-375787Y-162756D02*
Y-154013D01*
X-375800Y-154000D01*
G01X-355315Y-172598D02*
Y-177998D01*
G01X-356890Y-162756D02*
Y-157250D01*
X-356890Y-157350D01*
G01X-345866Y-172598D02*
Y-177998D01*
G01X-347441Y-157350D02*
X-347441Y-157250D01*
Y-162756D01*
G01X-317859Y-1500D02*
X-321859D01*
G01X-252050Y-175150D02*
X-254800D01*
G01X-252050Y-170650D02*
X-254800D01*
G01X-261511Y-180000D02*
X-265050D01*
X-265200Y-179850D01*
G01X-257889Y-180000D02*
X-254800D01*
G01D02*
X-251700D01*
G01X-256496Y-136730D02*
Y-142362D01*
G01D02*
Y-147990D01*
G01X-258732Y-104171D02*
X-258071Y-104831D01*
Y-110079D01*
G01X-247047Y-136730D02*
Y-142362D01*
G01D02*
Y-148090D01*
G01X-228950Y-170650D02*
X-226200D01*
G01X-226121Y-175150D02*
X-228950D01*
G01Y-179650D02*
X-228700Y-179900D01*
X-225400D01*
G01D02*
X-222011D01*
G01X-225400D02*
Y-179800D01*
G01X-237598Y-148090D02*
Y-142362D01*
G01X-228150Y-148090D02*
Y-142362D01*
G01D02*
Y-136730D01*
G01X-237598Y-142362D02*
Y-136730D01*
G01X-229724Y-110079D02*
Y-104976D01*
X-228932Y-104183D01*
G01X-218389Y-179900D02*
X-214600D01*
X-214500Y-179800D01*
G01X-177150Y-47161D02*
X-173939D01*
X-173800Y-47300D01*
G01X-177091Y-52350D02*
X-173250D01*
X-173200Y-52400D01*
G01X-182650Y-43550D02*
X-179800D01*
G01D02*
X-177161D01*
X-177150Y-43539D01*
G01X-179800Y-43550D02*
Y-43500D01*
G01X-179811Y-21300D02*
Y-24300D01*
X-180011Y-24500D01*
G01X-176350Y-29850D02*
Y-27200D01*
G01D02*
X-176389Y-27161D01*
Y-24500D01*
G01X-178811Y1000D02*
Y4300D01*
X-179011Y4500D01*
G01X-175200Y-4500D02*
Y-1900D01*
X-175100Y-1800D01*
G01D02*
X-175200Y-1700D01*
Y989D01*
X-175189Y1000D01*
G01X-173841Y-34470D02*
X-170200D01*
G01X-173941Y-10000D02*
X-170500D01*
G01X-173750Y-16500D02*
X-170300D01*
G01X-74921Y-171500D02*
X-74980Y-171441D01*
X-78400D01*
M02*
